FILE_TYPE = MACRO_DRAWING;
SET COLOR_WIRE YELLOW;
SET COLOR_PROP MONO;
SET COLOR_DOT WHITE;
SET COLOR_ARC YELLOW;
SET COLOR_BODY GREEN;
SET COLOR_NOTE MONO;
SET PROP_DISPLAY VALUE;
SET PAGE_NUMBER P247;
FORCEADD RES..2
R 2
(-7375 3800);
FORCEPROP 1 LASTPIN (-7375 3900) $PN 1
J 2
(-7380 3862);
DISPLAY 0.787234 (-7380 3862);
PAINT ORANGE (-7380 3862);
DISPLAY INVISIBLE (-7380 3862);
FORCEPROP 1 LASTPIN (-7375 3700) $PN 2
J 2
(-7380 3710);
DISPLAY 0.787234 (-7380 3710);
PAINT ORANGE (-7380 3710);
DISPLAY INVISIBLE (-7380 3710);
FORCEPROP 1 LAST PATH I1
J 2
(-7425 3975);
DISPLAY 0.978723 (-7425 3975);
PAINT WHITE (-7425 3975);
DISPLAY INVISIBLE (-7425 3975);
FORCEPROP 0 LAST ROOM CPU_FANS
J 0
(-7400 4025);
DISPLAY 1.021277 (-7400 4025);
PAINT ORANGE (-7400 4025);
DISPLAY INVISIBLE (-7400 4025);
FORCEPROP 0 LAST BOM_COST SM_THERM
J 0
(-7400 4125);
DISPLAY 1.021277 (-7400 4125);
PAINT ORANGE (-7400 4125);
DISPLAY INVISIBLE (-7400 4125);
FORCEPROP 2 LAST CDS_LIB mstr_discrete
J 0
(-7375 3800);
PAINT MONO (-7375 3800);
DISPLAY INVISIBLE (-7375 3800);
FORCEPROP 1 LAST PART_NUMBER G21796-072
J 2
(-7415 3675);
DISPLAY 0.617021 (-7415 3675);
PAINT BLUE (-7415 3675);
FORCEPROP 1 LAST TOLERANCE 1%
J 2
(-7420 3825);
DISPLAY 0.617021 (-7420 3825);
PAINT SKYBLUE (-7420 3825);
FORCEPROP 1 LAST LOCATION R6W10
J 2
(-7420 3925);
DISPLAY 0.617021 (-7420 3925);
PAINT AQUA (-7420 3925);
FORCEPROP 1 LAST VALUE 4.75K
J 2
(-7420 3875);
DISPLAY 0.617021 (-7420 3875);
PAINT SKYBLUE (-7420 3875);
FORCEPROP 1 LAST WATTAGE 1/16W
J 2
(-7415 3775);
DISPLAY 0.617021 (-7415 3775);
PAINT SKYBLUE (-7415 3775);
FORCEPROP 1 LAST MATERIAL CHIP
J 2
(-7415 3725);
DISPLAY 0.617021 (-7415 3725);
PAINT SKYBLUE (-7415 3725);
FORCEPROP 1 LAST PACK_TYPE 0402
J 2
(-7540 3775);
DISPLAY 0.617021 (-7540 3775);
PAINT SKYBLUE (-7540 3775);
FORCEADD RES..2
(-5250 4050);
FORCEPROP 1 LASTPIN (-5250 4150) $PN 1
J 0
(-5245 4112);
DISPLAY 0.787234 (-5245 4112);
PAINT ORANGE (-5245 4112);
DISPLAY INVISIBLE (-5245 4112);
FORCEPROP 1 LASTPIN (-5250 3950) $PN 2
J 0
(-5245 3960);
DISPLAY 0.787234 (-5245 3960);
PAINT ORANGE (-5245 3960);
DISPLAY INVISIBLE (-5245 3960);
FORCEPROP 0 LAST ROOM HOT_SWAP
J 0
(-5200 4275);
DISPLAY 1.021277 (-5200 4275);
PAINT ORANGE (-5200 4275);
DISPLAY INVISIBLE (-5200 4275);
FORCEPROP 0 LAST NO_XNET_CONNECTION 1
J 0
(-5200 4275);
PAINT MONO (-5200 4275);
DISPLAY INVISIBLE (-5200 4275);
FORCEPROP 2 LAST CDS_LIB mstr_discrete
J 0
(-5250 4050);
PAINT MONO (-5250 4050);
DISPLAY INVISIBLE (-5250 4050);
FORCEPROP 1 LAST PATH I10
J 0
(-5200 4225);
DISPLAY 0.978723 (-5200 4225);
PAINT WHITE (-5200 4225);
DISPLAY INVISIBLE (-5200 4225);
FORCEPROP 1 LAST PACK_TYPE 0402
J 0
(-5210 3875);
DISPLAY 0.617021 (-5210 3875);
PAINT SKYBLUE (-5210 3875);
FORCEPROP 1 LAST WATTAGE 1/16W
J 0
(-5210 4025);
DISPLAY 0.617021 (-5210 4025);
PAINT SKYBLUE (-5210 4025);
FORCEPROP 1 LAST MATERIAL EMPTY
J 0
(-5210 3975);
DISPLAY 0.617021 (-5210 3975);
PAINT RED (-5210 3975);
FORCEPROP 1 LAST PART_NUMBER G21796-072
J 0
(-5210 3925);
DISPLAY 0.617021 (-5210 3925);
PAINT BLUE (-5210 3925);
FORCEPROP 1 LAST VALUE 4.75K
J 0
(-5205 4125);
DISPLAY 0.617021 (-5205 4125);
PAINT SKYBLUE (-5205 4125);
FORCEPROP 1 LAST TOLERANCE 1%
J 0
(-5205 4075);
DISPLAY 0.617021 (-5205 4075);
PAINT SKYBLUE (-5205 4075);
FORCEPROP 1 LAST LOCATION R6W5
J 0
(-5205 4175);
DISPLAY 0.617021 (-5205 4175);
PAINT AQUA (-5205 4175);
FORCEADD RES..2
(-4850 4050);
FORCEPROP 1 LASTPIN (-4850 4150) $PN 1
J 0
(-4845 4112);
DISPLAY 0.787234 (-4845 4112);
PAINT ORANGE (-4845 4112);
DISPLAY INVISIBLE (-4845 4112);
FORCEPROP 1 LASTPIN (-4850 3950) $PN 2
J 0
(-4845 3960);
DISPLAY 0.787234 (-4845 3960);
PAINT ORANGE (-4845 3960);
DISPLAY INVISIBLE (-4845 3960);
FORCEPROP 0 LAST NO_XNET_CONNECTION 1
J 0
(-4800 4275);
PAINT MONO (-4800 4275);
DISPLAY INVISIBLE (-4800 4275);
FORCEPROP 0 LAST ROOM HOT_SWAP
J 0
(-4800 4275);
DISPLAY 1.021277 (-4800 4275);
PAINT ORANGE (-4800 4275);
DISPLAY INVISIBLE (-4800 4275);
FORCEPROP 2 LAST CDS_LIB mstr_discrete
J 0
(-4850 4050);
PAINT MONO (-4850 4050);
DISPLAY INVISIBLE (-4850 4050);
FORCEPROP 1 LAST PATH I11
J 0
(-4800 4225);
DISPLAY 0.978723 (-4800 4225);
PAINT WHITE (-4800 4225);
DISPLAY INVISIBLE (-4800 4225);
FORCEPROP 1 LAST PART_NUMBER G21796-072
J 0
(-4810 3925);
DISPLAY 0.617021 (-4810 3925);
PAINT BLUE (-4810 3925);
FORCEPROP 1 LAST PACK_TYPE 0402
J 0
(-4810 3875);
DISPLAY 0.617021 (-4810 3875);
PAINT SKYBLUE (-4810 3875);
FORCEPROP 1 LAST MATERIAL EMPTY
J 0
(-4810 3975);
DISPLAY 0.617021 (-4810 3975);
PAINT RED (-4810 3975);
FORCEPROP 1 LAST VALUE 4.75K
J 0
(-4805 4125);
DISPLAY 0.617021 (-4805 4125);
PAINT SKYBLUE (-4805 4125);
FORCEPROP 1 LAST TOLERANCE 1%
J 0
(-4805 4075);
DISPLAY 0.617021 (-4805 4075);
PAINT SKYBLUE (-4805 4075);
FORCEPROP 1 LAST WATTAGE 1/16W
J 0
(-4810 4025);
DISPLAY 0.617021 (-4810 4025);
PAINT SKYBLUE (-4810 4025);
FORCEPROP 1 LAST LOCATION R6W6
J 0
(-4805 4175);
DISPLAY 0.617021 (-4805 4175);
PAINT AQUA (-4805 4175);
FORCEADD P3V3_STBY..1
(-7375 4325);
FORCEPROP 3 LASTPIN (-7375 4275) SIG_NAME P3V3_STBY\g
J 0
(-7365 4285);
DISPLAY 0.659574 (-7365 4285);
PAINT MONO (-7365 4285);
DISPLAY INVISIBLE (-7365 4285);
FORCEPROP 2 LAST CDS_LIB mstr_symbols
J 0
(-7375 4325);
PAINT MONO (-7375 4325);
DISPLAY INVISIBLE (-7375 4325);
FORCEPROP 1 LAST SIZE 1B
J 0
(-7330 4347);
DISPLAY 0.340426 (-7330 4347);
PAINT GREEN (-7330 4347);
DISPLAY INVISIBLE (-7330 4347);
FORCEPROP 1 LAST VOLTAGE 3.3V
J 0
(-7420 4282);
DISPLAY 0.340426 (-7420 4282);
PAINT GREEN (-7420 4282);
DISPLAY INVISIBLE (-7420 4282);
FORCEPROP 1 LAST PATH I12
J 0
(-7330 4327);
DISPLAY 0.340426 (-7330 4327);
PAINT GREEN (-7330 4327);
DISPLAY INVISIBLE (-7330 4327);
FORCEPROP 1 LAST BODY_TYPE PLUMBING
J 0
(-7420 4282);
DISPLAY 0.340426 (-7420 4282);
PAINT GREEN (-7420 4282);
DISPLAY INVISIBLE (-7420 4282);
FORCEPROP 1 LAST HDL_POWER P3V3_STBY
J 0
(-7675 4200);
DISPLAY 0.872340 (-7675 4200);
PAINT ORANGE (-7675 4200);
DISPLAY INVISIBLE (-7675 4200);
FORCEADD GND..1
(-4850 3150);
FORCEPROP 3 LASTPIN (-4850 3200) SIG_NAME GND\g
J 0
(-4840 3210);
DISPLAY 0.659574 (-4840 3210);
PAINT MONO (-4840 3210);
DISPLAY INVISIBLE (-4840 3210);
FORCEPROP 1 LAST SIZE 1B
J 0
(-4775 3100);
DISPLAY 0.872340 (-4775 3100);
PAINT AQUA (-4775 3100);
DISPLAY INVISIBLE (-4775 3100);
FORCEPROP 2 LAST CDS_LIB mstr_symbols
J 0
(-4850 3150);
PAINT MONO (-4850 3150);
DISPLAY INVISIBLE (-4850 3150);
FORCEPROP 1 LAST VOLTAGE 0.0V
J 0
(-4895 3107);
DISPLAY 0.340426 (-4895 3107);
PAINT GREEN (-4895 3107);
DISPLAY INVISIBLE (-4895 3107);
FORCEPROP 1 LAST PATH I13
J 0
(-4775 3150);
DISPLAY 0.872340 (-4775 3150);
PAINT AQUA (-4775 3150);
DISPLAY INVISIBLE (-4775 3150);
FORCEPROP 1 LAST BODY_TYPE PLUMBING
J 0
(-4895 3107);
DISPLAY 0.340426 (-4895 3107);
PAINT GREEN (-4895 3107);
DISPLAY INVISIBLE (-4895 3107);
FORCEPROP 1 LAST HDL_POWER GND
J 0
(-4850 3300);
DISPLAY 0.872340 (-4850 3300);
PAINT GREEN (-4850 3300);
DISPLAY INVISIBLE (-4850 3300);
FORCEADD GND..1
(-3600 3750);
FORCEPROP 3 LASTPIN (-3600 3800) SIG_NAME GND\g
J 0
(-3590 3810);
DISPLAY 0.659574 (-3590 3810);
PAINT MONO (-3590 3810);
DISPLAY INVISIBLE (-3590 3810);
FORCEPROP 2 LAST CDS_LIB mstr_symbols
J 0
(-3600 3750);
PAINT MONO (-3600 3750);
DISPLAY INVISIBLE (-3600 3750);
FORCEPROP 1 LAST SIZE 1B
J 0
(-3525 3700);
DISPLAY 1.170213 (-3525 3700);
PAINT AQUA (-3525 3700);
DISPLAY INVISIBLE (-3525 3700);
FORCEPROP 1 LAST VOLTAGE 0.0V
J 0
(-3645 3707);
DISPLAY 0.340426 (-3645 3707);
PAINT GREEN (-3645 3707);
DISPLAY INVISIBLE (-3645 3707);
FORCEPROP 1 LAST PATH I17
J 0
(-3525 3750);
DISPLAY 0.872340 (-3525 3750);
PAINT AQUA (-3525 3750);
DISPLAY INVISIBLE (-3525 3750);
FORCEPROP 1 LAST BODY_TYPE PLUMBING
J 0
(-3645 3707);
DISPLAY 0.340426 (-3645 3707);
PAINT GREEN (-3645 3707);
DISPLAY INVISIBLE (-3645 3707);
FORCEPROP 1 LAST HDL_POWER GND
J 0
(-3600 3900);
DISPLAY 1.170213 (-3600 3900);
PAINT GREEN (-3600 3900);
DISPLAY INVISIBLE (-3600 3900);
FORCEADD CAP..1
(-3600 3950);
FORCEPROP 1 LASTPIN (-3600 4050) $PN 1
J 0
(-3590 4030);
DISPLAY 0.787234 (-3590 4030);
PAINT ORANGE (-3590 4030);
DISPLAY INVISIBLE (-3590 4030);
FORCEPROP 1 LASTPIN (-3600 3850) $PN 2
J 0
(-3590 3830);
DISPLAY 0.787234 (-3590 3830);
PAINT ORANGE (-3590 3830);
DISPLAY INVISIBLE (-3590 3830);
FORCEPROP 2 LAST CDS_LIB mstr_discrete
J 0
(-3600 3950);
PAINT MONO (-3600 3950);
DISPLAY INVISIBLE (-3600 3950);
FORCEPROP 1 LAST PATH I18
J 0
(-3550 4100);
DISPLAY 0.978723 (-3550 4100);
PAINT WHITE (-3550 4100);
DISPLAY INVISIBLE (-3550 4100);
FORCEPROP 2 LAST BOM_COST SM_THERM
J 0
(-3550 4150);
DISPLAY 1.021277 (-3550 4150);
PAINT ORANGE (-3550 4150);
DISPLAY INVISIBLE (-3550 4150);
FORCEPROP 2 LAST ROOM CPUFANS
J 0
(-3550 4100);
DISPLAY 1.021277 (-3550 4100);
PAINT ORANGE (-3550 4100);
DISPLAY INVISIBLE (-3550 4100);
FORCEPROP 1 LAST LOCATION C6W1
J 0
(-3550 4050);
DISPLAY 0.617021 (-3550 4050);
PAINT AQUA (-3550 4050);
FORCEPROP 1 LAST VALUE 0.1UF
J 0
(-3550 4000);
DISPLAY 0.617021 (-3550 4000);
PAINT SKYBLUE (-3550 4000);
FORCEPROP 1 LAST VOLTAGE 16V
J 0
(-3550 3950);
DISPLAY 0.617021 (-3550 3950);
PAINT SKYBLUE (-3550 3950);
FORCEPROP 1 LAST PART_NUMBER A36096-030
J 0
(-3550 3800);
DISPLAY 0.617021 (-3550 3800);
PAINT BLUE (-3550 3800);
FORCEPROP 1 LAST MATERIAL X7R
J 0
(-3550 3850);
DISPLAY 0.617021 (-3550 3850);
PAINT SKYBLUE (-3550 3850);
FORCEPROP 1 LAST TOLERANCE 10%
J 0
(-3550 3900);
DISPLAY 0.617021 (-3550 3900);
PAINT SKYBLUE (-3550 3900);
FORCEPROP 1 LAST PACK_TYPE 0402LF
J 0
(-3550 3750);
DISPLAY 0.617021 (-3550 3750);
PAINT SKYBLUE (-3550 3750);
FORCEADD P3V3_STBY..1
(-3600 4325);
FORCEPROP 3 LASTPIN (-3600 4275) SIG_NAME P3V3_STBY\g
J 0
(-3590 4285);
DISPLAY 0.659574 (-3590 4285);
PAINT MONO (-3590 4285);
DISPLAY INVISIBLE (-3590 4285);
FORCEPROP 2 LAST CDS_LIB mstr_symbols
J 0
(-3600 4325);
PAINT MONO (-3600 4325);
DISPLAY INVISIBLE (-3600 4325);
FORCEPROP 1 LAST SIZE 1B
J 0
(-3555 4347);
DISPLAY 0.340426 (-3555 4347);
PAINT GREEN (-3555 4347);
DISPLAY INVISIBLE (-3555 4347);
FORCEPROP 1 LAST VOLTAGE 3.3V
J 0
(-3645 4282);
DISPLAY 0.340426 (-3645 4282);
PAINT GREEN (-3645 4282);
DISPLAY INVISIBLE (-3645 4282);
FORCEPROP 1 LAST PATH I19
J 0
(-3555 4327);
DISPLAY 0.340426 (-3555 4327);
PAINT GREEN (-3555 4327);
DISPLAY INVISIBLE (-3555 4327);
FORCEPROP 1 LAST BODY_TYPE PLUMBING
J 0
(-3645 4282);
DISPLAY 0.340426 (-3645 4282);
PAINT GREEN (-3645 4282);
DISPLAY INVISIBLE (-3645 4282);
FORCEPROP 1 LAST HDL_POWER P3V3_STBY
J 0
(-3900 4200);
DISPLAY 0.872340 (-3900 4200);
PAINT ORANGE (-3900 4200);
DISPLAY INVISIBLE (-3900 4200);
FORCEADD GND..1
(-1900 3000);
FORCEPROP 3 LASTPIN (-1900 3050) SIG_NAME GND\g
J 0
(-1890 3060);
DISPLAY 0.659574 (-1890 3060);
PAINT MONO (-1890 3060);
DISPLAY INVISIBLE (-1890 3060);
FORCEPROP 2 LAST CDS_LIB mstr_symbols
J 0
(-1900 3000);
PAINT MONO (-1900 3000);
DISPLAY INVISIBLE (-1900 3000);
FORCEPROP 1 LAST SIZE 1B
J 0
(-1825 2950);
DISPLAY 0.872340 (-1825 2950);
PAINT AQUA (-1825 2950);
DISPLAY INVISIBLE (-1825 2950);
FORCEPROP 1 LAST VOLTAGE 0.0V
J 0
(-1945 2957);
DISPLAY 0.340426 (-1945 2957);
PAINT GREEN (-1945 2957);
DISPLAY INVISIBLE (-1945 2957);
FORCEPROP 1 LAST PATH I20
J 0
(-1825 3000);
DISPLAY 0.872340 (-1825 3000);
PAINT AQUA (-1825 3000);
DISPLAY INVISIBLE (-1825 3000);
FORCEPROP 1 LAST BODY_TYPE PLUMBING
J 0
(-1945 2957);
DISPLAY 0.340426 (-1945 2957);
PAINT GREEN (-1945 2957);
DISPLAY INVISIBLE (-1945 2957);
FORCEPROP 1 LAST HDL_POWER GND
J 0
(-1900 3150);
DISPLAY 0.872340 (-1900 3150);
PAINT GREEN (-1900 3150);
DISPLAY INVISIBLE (-1900 3150);
FORCEADD OFFPAGE..2
(-1525 3550);
FORCEPROP 2 LAST CDS_LIB mstr_standard
J 0
(-1525 3550);
PAINT MONO (-1525 3550);
DISPLAY INVISIBLE (-1525 3550);
FORCEPROP 2 LAST PATH I21
J 0
(-1350 3625);
DISPLAY 1.021277 (-1350 3625);
PAINT ORANGE (-1350 3625);
DISPLAY INVISIBLE (-1350 3625);
FORCEPROP 1 LAST OFFPAGE TRUE
J 0
(-1200 3425);
DISPLAY 0.872340 (-1200 3425);
PAINT GREEN (-1200 3425);
DISPLAY INVISIBLE (-1200 3425);
FORCEPROP 1 LAST COMMENT_BODY TRUE
J 0
(-1570 3455);
DISPLAY 0.872340 (-1570 3455);
PAINT GREEN (-1570 3455);
DISPLAY INVISIBLE (-1570 3455);
FORCEPROP 2 LAST $XR0 175 
J 0
(-1336 3550);
DISPLAY 0.638298 (-1336 3550);
PAINT MONO (-1336 3550);
FORCEADD OFFPAGE..2
(-1525 3600);
FORCEPROP 2 LAST CDS_LIB mstr_standard
J 0
(-1525 3600);
PAINT MONO (-1525 3600);
DISPLAY INVISIBLE (-1525 3600);
FORCEPROP 2 LAST PATH I22
J 0
(-1350 3675);
DISPLAY 1.021277 (-1350 3675);
PAINT ORANGE (-1350 3675);
DISPLAY INVISIBLE (-1350 3675);
FORCEPROP 1 LAST OFFPAGE TRUE
J 0
(-1200 3475);
DISPLAY 0.872340 (-1200 3475);
PAINT GREEN (-1200 3475);
DISPLAY INVISIBLE (-1200 3475);
FORCEPROP 1 LAST COMMENT_BODY TRUE
J 0
(-1570 3505);
DISPLAY 0.872340 (-1570 3505);
PAINT GREEN (-1570 3505);
DISPLAY INVISIBLE (-1570 3505);
FORCEPROP 2 LAST $XR1 155 
J 0
(-1216 3600);
DISPLAY 0.638298 (-1216 3600);
PAINT MONO (-1216 3600);
FORCEPROP 2 LAST $XR2 190 
J 0
(-1096 3600);
DISPLAY 0.638298 (-1096 3600);
PAINT MONO (-1096 3600);
FORCEPROP 2 LAST $XR3 175 
J 0
(-976 3600);
DISPLAY 0.638298 (-976 3600);
PAINT MONO (-976 3600);
FORCEPROP 2 LAST $XR0 111 
J 0
(-1336 3600);
DISPLAY 0.638298 (-1336 3600);
PAINT MONO (-1336 3600);
FORCEADD OFFPAGE..3
(-1525 3750);
FORCEPROP 2 LAST CDS_LIB mstr_standard
J 0
(-1525 3750);
PAINT MONO (-1525 3750);
DISPLAY INVISIBLE (-1525 3750);
FORCEPROP 2 LAST PATH I23
J 0
(-1325 3825);
DISPLAY 1.021277 (-1325 3825);
PAINT ORANGE (-1325 3825);
DISPLAY INVISIBLE (-1325 3825);
FORCEPROP 1 LAST OFFPAGE TRUE
J 0
(-1200 3625);
DISPLAY 0.872340 (-1200 3625);
PAINT GREEN (-1200 3625);
DISPLAY INVISIBLE (-1200 3625);
FORCEPROP 1 LAST COMMENT_BODY TRUE
J 0
(-1575 3650);
DISPLAY 0.872340 (-1575 3650);
PAINT GREEN (-1575 3650);
DISPLAY INVISIBLE (-1575 3650);
FORCEPROP 2 LAST $XR0 155 
J 0
(-1311 3750);
DISPLAY 0.638298 (-1311 3750);
PAINT MONO (-1311 3750);
FORCEADD OFFPAGE..3
(-1525 3700);
FORCEPROP 1 LAST COMMENT_BODY TRUE
J 0
(-1575 3600);
DISPLAY 0.872340 (-1575 3600);
PAINT GREEN (-1575 3600);
DISPLAY INVISIBLE (-1575 3600);
FORCEPROP 1 LAST OFFPAGE TRUE
J 0
(-1200 3575);
DISPLAY 0.872340 (-1200 3575);
PAINT GREEN (-1200 3575);
DISPLAY INVISIBLE (-1200 3575);
FORCEPROP 2 LAST PATH I24
J 0
(-1325 3775);
DISPLAY 1.021277 (-1325 3775);
PAINT ORANGE (-1325 3775);
DISPLAY INVISIBLE (-1325 3775);
FORCEPROP 2 LAST CDS_LIB mstr_standard
J 0
(-1525 3700);
PAINT MONO (-1525 3700);
DISPLAY INVISIBLE (-1525 3700);
FORCEPROP 2 LAST $XR0 155 
J 0
(-1311 3700);
DISPLAY 0.638298 (-1311 3700);
PAINT MONO (-1311 3700);
FORCEADD OFFPAGE..3
(-1525 3800);
FORCEPROP 2 LAST CDS_LIB mstr_standard
J 0
(-1525 3800);
PAINT MONO (-1525 3800);
DISPLAY INVISIBLE (-1525 3800);
FORCEPROP 2 LAST PATH I25
J 0
(-1325 3875);
DISPLAY 1.021277 (-1325 3875);
PAINT ORANGE (-1325 3875);
DISPLAY INVISIBLE (-1325 3875);
FORCEPROP 1 LAST OFFPAGE TRUE
J 0
(-1200 3675);
DISPLAY 0.872340 (-1200 3675);
PAINT GREEN (-1200 3675);
DISPLAY INVISIBLE (-1200 3675);
FORCEPROP 1 LAST COMMENT_BODY TRUE
J 0
(-1575 3700);
DISPLAY 0.872340 (-1575 3700);
PAINT GREEN (-1575 3700);
DISPLAY INVISIBLE (-1575 3700);
FORCEPROP 2 LAST $XR0 155 
J 0
(-1311 3800);
DISPLAY 0.638298 (-1311 3800);
PAINT MONO (-1311 3800);
FORCEADD OFFPAGE..3
(-1525 3900);
FORCEPROP 2 LAST CDS_LIB mstr_standard
J 0
(-1525 3900);
PAINT MONO (-1525 3900);
DISPLAY INVISIBLE (-1525 3900);
FORCEPROP 2 LAST PATH I26
J 0
(-1325 3975);
DISPLAY 1.021277 (-1325 3975);
PAINT ORANGE (-1325 3975);
DISPLAY INVISIBLE (-1325 3975);
FORCEPROP 1 LAST OFFPAGE TRUE
J 0
(-1200 3775);
DISPLAY 0.872340 (-1200 3775);
PAINT GREEN (-1200 3775);
DISPLAY INVISIBLE (-1200 3775);
FORCEPROP 1 LAST COMMENT_BODY TRUE
J 0
(-1575 3800);
DISPLAY 0.872340 (-1575 3800);
PAINT GREEN (-1575 3800);
DISPLAY INVISIBLE (-1575 3800);
FORCEPROP 2 LAST $XR0 155 
J 0
(-1311 3900);
DISPLAY 0.638298 (-1311 3900);
PAINT MONO (-1311 3900);
FORCEADD OFFPAGE..3
(-1525 3850);
FORCEPROP 2 LAST CDS_LIB mstr_standard
J 0
(-1525 3850);
PAINT MONO (-1525 3850);
DISPLAY INVISIBLE (-1525 3850);
FORCEPROP 2 LAST PATH I27
J 0
(-1325 3925);
DISPLAY 1.021277 (-1325 3925);
PAINT ORANGE (-1325 3925);
DISPLAY INVISIBLE (-1325 3925);
FORCEPROP 1 LAST OFFPAGE TRUE
J 0
(-1200 3725);
DISPLAY 0.872340 (-1200 3725);
PAINT GREEN (-1200 3725);
DISPLAY INVISIBLE (-1200 3725);
FORCEPROP 1 LAST COMMENT_BODY TRUE
J 0
(-1575 3750);
DISPLAY 0.872340 (-1575 3750);
PAINT GREEN (-1575 3750);
DISPLAY INVISIBLE (-1575 3750);
FORCEPROP 2 LAST $XR0 155 
J 0
(-1311 3850);
DISPLAY 0.638298 (-1311 3850);
PAINT MONO (-1311 3850);
FORCEADD OFFPAGE..3
(-1525 3950);
FORCEPROP 2 LAST CDS_LIB mstr_standard
J 0
(-1525 3950);
PAINT MONO (-1525 3950);
DISPLAY INVISIBLE (-1525 3950);
FORCEPROP 2 LAST PATH I28
J 0
(-1325 4025);
DISPLAY 1.021277 (-1325 4025);
PAINT ORANGE (-1325 4025);
DISPLAY INVISIBLE (-1325 4025);
FORCEPROP 1 LAST OFFPAGE TRUE
J 0
(-1200 3825);
DISPLAY 0.872340 (-1200 3825);
PAINT GREEN (-1200 3825);
DISPLAY INVISIBLE (-1200 3825);
FORCEPROP 1 LAST COMMENT_BODY TRUE
J 0
(-1575 3850);
DISPLAY 0.872340 (-1575 3850);
PAINT GREEN (-1575 3850);
DISPLAY INVISIBLE (-1575 3850);
FORCEPROP 2 LAST $XR0 155 
J 0
(-1311 3950);
DISPLAY 0.638298 (-1311 3950);
PAINT MONO (-1311 3950);
FORCEADD OFFPAGE..3
(-1525 4000);
FORCEPROP 2 LAST CDS_LIB mstr_standard
J 0
(-1525 4000);
PAINT MONO (-1525 4000);
DISPLAY INVISIBLE (-1525 4000);
FORCEPROP 2 LAST PATH I29
J 0
(-1325 4075);
DISPLAY 1.021277 (-1325 4075);
PAINT ORANGE (-1325 4075);
DISPLAY INVISIBLE (-1325 4075);
FORCEPROP 1 LAST OFFPAGE TRUE
J 0
(-1200 3875);
DISPLAY 0.872340 (-1200 3875);
PAINT GREEN (-1200 3875);
DISPLAY INVISIBLE (-1200 3875);
FORCEPROP 1 LAST COMMENT_BODY TRUE
J 0
(-1575 3900);
DISPLAY 0.872340 (-1575 3900);
PAINT GREEN (-1575 3900);
DISPLAY INVISIBLE (-1575 3900);
FORCEPROP 2 LAST $XR0 155 
J 0
(-1311 4000);
DISPLAY 0.638298 (-1311 4000);
PAINT MONO (-1311 4000);
FORCEADD RES..2
R 2
(-5650 3425);
FORCEPROP 1 LASTPIN (-5650 3525) $PN 1
J 2
(-5655 3487);
DISPLAY 0.787234 (-5655 3487);
PAINT ORANGE (-5655 3487);
DISPLAY INVISIBLE (-5655 3487);
FORCEPROP 1 LASTPIN (-5650 3325) $PN 2
J 2
(-5655 3335);
DISPLAY 0.787234 (-5655 3335);
PAINT ORANGE (-5655 3335);
DISPLAY INVISIBLE (-5655 3335);
FORCEPROP 0 LAST BOM_COST SM_THERM
J 0
(-5675 3750);
DISPLAY 1.021277 (-5675 3750);
PAINT ORANGE (-5675 3750);
DISPLAY INVISIBLE (-5675 3750);
FORCEPROP 0 LAST ROOM CPU_FANS
J 0
(-5675 3650);
DISPLAY 1.021277 (-5675 3650);
PAINT ORANGE (-5675 3650);
DISPLAY INVISIBLE (-5675 3650);
FORCEPROP 2 LAST CDS_LIB mstr_discrete
J 0
(-5650 3425);
PAINT MONO (-5650 3425);
DISPLAY INVISIBLE (-5650 3425);
FORCEPROP 1 LAST PATH I3
J 2
(-5700 3600);
DISPLAY 0.978723 (-5700 3600);
PAINT WHITE (-5700 3600);
DISPLAY INVISIBLE (-5700 3600);
FORCEPROP 1 LAST LOCATION R6W7
J 2
(-5695 3550);
DISPLAY 0.617021 (-5695 3550);
PAINT AQUA (-5695 3550);
FORCEPROP 1 LAST VALUE 4.75K
J 2
(-5695 3500);
DISPLAY 0.617021 (-5695 3500);
PAINT SKYBLUE (-5695 3500);
FORCEPROP 1 LAST TOLERANCE 1%
J 2
(-5695 3450);
DISPLAY 0.617021 (-5695 3450);
PAINT SKYBLUE (-5695 3450);
FORCEPROP 1 LAST WATTAGE 1/16W
J 2
(-5690 3400);
DISPLAY 0.617021 (-5690 3400);
PAINT SKYBLUE (-5690 3400);
FORCEPROP 1 LAST MATERIAL CHIP
J 2
(-5690 3350);
DISPLAY 0.617021 (-5690 3350);
PAINT SKYBLUE (-5690 3350);
FORCEPROP 1 LAST PACK_TYPE 0402
J 2
(-5815 3400);
DISPLAY 0.617021 (-5815 3400);
PAINT SKYBLUE (-5815 3400);
FORCEPROP 1 LAST PART_NUMBER G21796-072
J 2
(-5690 3300);
DISPLAY 0.617021 (-5690 3300);
PAINT BLUE (-5690 3300);
FORCEADD OFFPAGE..3
(-1525 4050);
FORCEPROP 2 LAST CDS_LIB mstr_standard
J 0
(-1525 4050);
PAINT MONO (-1525 4050);
DISPLAY INVISIBLE (-1525 4050);
FORCEPROP 2 LAST PATH I30
J 0
(-1325 4125);
DISPLAY 1.021277 (-1325 4125);
PAINT ORANGE (-1325 4125);
DISPLAY INVISIBLE (-1325 4125);
FORCEPROP 1 LAST OFFPAGE TRUE
J 0
(-1200 3925);
DISPLAY 0.872340 (-1200 3925);
PAINT GREEN (-1200 3925);
DISPLAY INVISIBLE (-1200 3925);
FORCEPROP 1 LAST COMMENT_BODY TRUE
J 0
(-1575 3950);
DISPLAY 0.872340 (-1575 3950);
PAINT GREEN (-1575 3950);
DISPLAY INVISIBLE (-1575 3950);
FORCEPROP 2 LAST $XR0 155 
J 0
(-1311 4050);
DISPLAY 0.638298 (-1311 4050);
PAINT MONO (-1311 4050);
FORCEADD GND..1
(-5650 3175);
FORCEPROP 3 LASTPIN (-5650 3225) SIG_NAME GND\g
J 0
(-5640 3235);
DISPLAY 0.659574 (-5640 3235);
PAINT MONO (-5640 3235);
DISPLAY INVISIBLE (-5640 3235);
FORCEPROP 1 LAST SIZE 1B
J 0
(-5575 3125);
DISPLAY 0.872340 (-5575 3125);
PAINT AQUA (-5575 3125);
DISPLAY INVISIBLE (-5575 3125);
FORCEPROP 2 LAST CDS_LIB mstr_symbols
J 0
(-5650 3175);
PAINT MONO (-5650 3175);
DISPLAY INVISIBLE (-5650 3175);
FORCEPROP 1 LAST VOLTAGE 0.0V
J 0
(-5695 3132);
DISPLAY 0.340426 (-5695 3132);
PAINT GREEN (-5695 3132);
DISPLAY INVISIBLE (-5695 3132);
FORCEPROP 1 LAST PATH I4
J 0
(-5575 3175);
DISPLAY 0.872340 (-5575 3175);
PAINT AQUA (-5575 3175);
DISPLAY INVISIBLE (-5575 3175);
FORCEPROP 1 LAST BODY_TYPE PLUMBING
J 0
(-5695 3132);
DISPLAY 0.340426 (-5695 3132);
PAINT GREEN (-5695 3132);
DISPLAY INVISIBLE (-5695 3132);
FORCEPROP 1 LAST HDL_POWER GND
J 0
(-5650 3325);
DISPLAY 0.872340 (-5650 3325);
PAINT GREEN (-5650 3325);
DISPLAY INVISIBLE (-5650 3325);
FORCEADD RES..2
(-5650 4050);
FORCEPROP 1 LASTPIN (-5650 4150) $PN 1
J 0
(-5645 4112);
DISPLAY 0.787234 (-5645 4112);
PAINT ORANGE (-5645 4112);
DISPLAY INVISIBLE (-5645 4112);
FORCEPROP 1 LASTPIN (-5650 3950) $PN 2
J 0
(-5645 3960);
DISPLAY 0.787234 (-5645 3960);
PAINT ORANGE (-5645 3960);
DISPLAY INVISIBLE (-5645 3960);
FORCEPROP 2 LAST CDS_LIB mstr_discrete
J 0
(-5650 4050);
PAINT MONO (-5650 4050);
DISPLAY INVISIBLE (-5650 4050);
FORCEPROP 1 LAST PATH I5
J 0
(-5600 4225);
DISPLAY 0.978723 (-5600 4225);
PAINT WHITE (-5600 4225);
DISPLAY INVISIBLE (-5600 4225);
FORCEPROP 0 LAST ROOM HOT_SWAP
J 0
(-5600 4275);
DISPLAY 1.021277 (-5600 4275);
PAINT ORANGE (-5600 4275);
DISPLAY INVISIBLE (-5600 4275);
FORCEPROP 0 LAST NO_XNET_CONNECTION 1
J 0
(-5600 4275);
PAINT MONO (-5600 4275);
DISPLAY INVISIBLE (-5600 4275);
FORCEPROP 1 LAST PART_NUMBER G21796-072
J 0
(-5610 3925);
DISPLAY 0.617021 (-5610 3925);
PAINT BLUE (-5610 3925);
FORCEPROP 1 LAST PACK_TYPE 0402
J 0
(-5610 3875);
DISPLAY 0.617021 (-5610 3875);
PAINT SKYBLUE (-5610 3875);
FORCEPROP 1 LAST WATTAGE 1/16W
J 0
(-5610 4025);
DISPLAY 0.617021 (-5610 4025);
PAINT SKYBLUE (-5610 4025);
FORCEPROP 1 LAST LOCATION R6W4
J 0
(-5605 4175);
DISPLAY 0.617021 (-5605 4175);
PAINT AQUA (-5605 4175);
FORCEPROP 1 LAST VALUE 4.75K
J 0
(-5605 4125);
DISPLAY 0.617021 (-5605 4125);
PAINT SKYBLUE (-5605 4125);
FORCEPROP 1 LAST TOLERANCE 1%
J 0
(-5605 4075);
DISPLAY 0.617021 (-5605 4075);
PAINT SKYBLUE (-5605 4075);
FORCEPROP 1 LAST MATERIAL EMPTY
J 0
(-5610 3975);
DISPLAY 0.617021 (-5610 3975);
PAINT RED (-5610 3975);
FORCEADD P3V3_STBY..1
(-5650 4325);
FORCEPROP 3 LASTPIN (-5650 4275) SIG_NAME P3V3_STBY\g
J 0
(-5640 4285);
DISPLAY 0.659574 (-5640 4285);
PAINT MONO (-5640 4285);
DISPLAY INVISIBLE (-5640 4285);
FORCEPROP 1 LAST SIZE 1B
J 0
(-5605 4347);
DISPLAY 0.340426 (-5605 4347);
PAINT GREEN (-5605 4347);
DISPLAY INVISIBLE (-5605 4347);
FORCEPROP 2 LAST CDS_LIB mstr_symbols
J 0
(-5650 4325);
PAINT MONO (-5650 4325);
DISPLAY INVISIBLE (-5650 4325);
FORCEPROP 1 LAST VOLTAGE 3.3V
J 0
(-5695 4282);
DISPLAY 0.340426 (-5695 4282);
PAINT GREEN (-5695 4282);
DISPLAY INVISIBLE (-5695 4282);
FORCEPROP 1 LAST PATH I6
J 0
(-5605 4327);
DISPLAY 0.340426 (-5605 4327);
PAINT GREEN (-5605 4327);
DISPLAY INVISIBLE (-5605 4327);
FORCEPROP 1 LAST BODY_TYPE PLUMBING
J 0
(-5695 4282);
DISPLAY 0.340426 (-5695 4282);
PAINT GREEN (-5695 4282);
DISPLAY INVISIBLE (-5695 4282);
FORCEPROP 1 LAST HDL_POWER P3V3_STBY
J 0
(-5950 4200);
DISPLAY 0.872340 (-5950 4200);
PAINT ORANGE (-5950 4200);
DISPLAY INVISIBLE (-5950 4200);
FORCEADD RES..2
(-7150 3800);
FORCEPROP 1 LASTPIN (-7150 3900) $PN 1
J 0
(-7145 3862);
DISPLAY 0.787234 (-7145 3862);
PAINT ORANGE (-7145 3862);
DISPLAY INVISIBLE (-7145 3862);
FORCEPROP 1 LASTPIN (-7150 3700) $PN 2
J 0
(-7145 3710);
DISPLAY 0.787234 (-7145 3710);
PAINT ORANGE (-7145 3710);
DISPLAY INVISIBLE (-7145 3710);
FORCEPROP 0 LAST NO_XNET_CONNECTION 1
J 0
(-7100 4025);
PAINT MONO (-7100 4025);
DISPLAY INVISIBLE (-7100 4025);
FORCEPROP 0 LAST ROOM HOT_SWAP
J 0
(-7100 4025);
DISPLAY 1.021277 (-7100 4025);
PAINT ORANGE (-7100 4025);
DISPLAY INVISIBLE (-7100 4025);
FORCEPROP 1 LAST PATH I67
J 0
(-7100 3975);
DISPLAY 0.978723 (-7100 3975);
PAINT WHITE (-7100 3975);
DISPLAY INVISIBLE (-7100 3975);
FORCEPROP 2 LAST CDS_LIB mstr_discrete
J 0
(-7150 3800);
PAINT MONO (-7150 3800);
DISPLAY INVISIBLE (-7150 3800);
FORCEPROP 1 LAST PART_NUMBER G21796-072
J 0
(-7110 3675);
DISPLAY 0.617021 (-7110 3675);
PAINT BLUE (-7110 3675);
FORCEPROP 1 LAST PACK_TYPE 0402
J 0
(-7110 3625);
DISPLAY 0.617021 (-7110 3625);
PAINT SKYBLUE (-7110 3625);
FORCEPROP 1 LAST TOLERANCE 1%
J 0
(-7105 3825);
DISPLAY 0.617021 (-7105 3825);
PAINT SKYBLUE (-7105 3825);
FORCEPROP 1 LAST WATTAGE 1/16W
J 0
(-7110 3775);
DISPLAY 0.617021 (-7110 3775);
PAINT SKYBLUE (-7110 3775);
FORCEPROP 1 LAST MATERIAL EMPTY
J 0
(-7110 3725);
DISPLAY 0.617021 (-7110 3725);
PAINT RED (-7110 3725);
FORCEPROP 1 LAST LOCATION R6W11
J 0
(-7105 3925);
DISPLAY 0.617021 (-7105 3925);
PAINT AQUA (-7105 3925);
FORCEPROP 1 LAST VALUE 4.75K
J 0
(-7105 3875);
DISPLAY 0.617021 (-7105 3875);
PAINT SKYBLUE (-7105 3875);
FORCEADD RES..2
(-6850 3800);
FORCEPROP 1 LASTPIN (-6850 3900) $PN 1
J 0
(-6845 3862);
DISPLAY 0.787234 (-6845 3862);
PAINT ORANGE (-6845 3862);
DISPLAY INVISIBLE (-6845 3862);
FORCEPROP 1 LASTPIN (-6850 3700) $PN 2
J 0
(-6845 3710);
DISPLAY 0.787234 (-6845 3710);
PAINT ORANGE (-6845 3710);
DISPLAY INVISIBLE (-6845 3710);
FORCEPROP 0 LAST NO_XNET_CONNECTION 1
J 0
(-6800 4025);
PAINT MONO (-6800 4025);
DISPLAY INVISIBLE (-6800 4025);
FORCEPROP 0 LAST ROOM HOT_SWAP
J 0
(-6800 4025);
DISPLAY 1.021277 (-6800 4025);
PAINT ORANGE (-6800 4025);
DISPLAY INVISIBLE (-6800 4025);
FORCEPROP 1 LAST PATH I68
J 0
(-6800 3975);
DISPLAY 0.978723 (-6800 3975);
PAINT WHITE (-6800 3975);
DISPLAY INVISIBLE (-6800 3975);
FORCEPROP 2 LAST CDS_LIB mstr_discrete
J 0
(-6850 3800);
PAINT MONO (-6850 3800);
DISPLAY INVISIBLE (-6850 3800);
FORCEPROP 1 LAST PART_NUMBER G21796-072
J 0
(-6810 3675);
DISPLAY 0.617021 (-6810 3675);
PAINT BLUE (-6810 3675);
FORCEPROP 1 LAST MATERIAL EMPTY
J 0
(-6810 3725);
DISPLAY 0.617021 (-6810 3725);
PAINT RED (-6810 3725);
FORCEPROP 1 LAST WATTAGE 1/16W
J 0
(-6810 3775);
DISPLAY 0.617021 (-6810 3775);
PAINT SKYBLUE (-6810 3775);
FORCEPROP 1 LAST VALUE 4.75K
J 0
(-6805 3875);
DISPLAY 0.617021 (-6805 3875);
PAINT SKYBLUE (-6805 3875);
FORCEPROP 1 LAST TOLERANCE 1%
J 0
(-6805 3825);
DISPLAY 0.617021 (-6805 3825);
PAINT SKYBLUE (-6805 3825);
FORCEPROP 1 LAST PACK_TYPE 0402
J 0
(-6810 3625);
DISPLAY 0.617021 (-6810 3625);
PAINT SKYBLUE (-6810 3625);
FORCEPROP 1 LAST LOCATION R6W12
J 0
(-6805 3925);
DISPLAY 0.617021 (-6805 3925);
PAINT AQUA (-6805 3925);
FORCEADD GND..1
(-5250 3175);
FORCEPROP 3 LASTPIN (-5250 3225) SIG_NAME GND\g
J 0
(-5240 3235);
DISPLAY 0.659574 (-5240 3235);
PAINT MONO (-5240 3235);
DISPLAY INVISIBLE (-5240 3235);
FORCEPROP 1 LAST SIZE 1B
J 0
(-5175 3125);
DISPLAY 0.872340 (-5175 3125);
PAINT AQUA (-5175 3125);
DISPLAY INVISIBLE (-5175 3125);
FORCEPROP 2 LAST CDS_LIB mstr_symbols
J 0
(-5250 3175);
PAINT MONO (-5250 3175);
DISPLAY INVISIBLE (-5250 3175);
FORCEPROP 1 LAST VOLTAGE 0.0V
J 0
(-5295 3132);
DISPLAY 0.340426 (-5295 3132);
PAINT GREEN (-5295 3132);
DISPLAY INVISIBLE (-5295 3132);
FORCEPROP 1 LAST PATH I7
J 0
(-5175 3175);
DISPLAY 0.872340 (-5175 3175);
PAINT AQUA (-5175 3175);
DISPLAY INVISIBLE (-5175 3175);
FORCEPROP 1 LAST BODY_TYPE PLUMBING
J 0
(-5295 3132);
DISPLAY 0.340426 (-5295 3132);
PAINT GREEN (-5295 3132);
DISPLAY INVISIBLE (-5295 3132);
FORCEPROP 1 LAST HDL_POWER GND
J 0
(-5250 3325);
DISPLAY 0.872340 (-5250 3325);
PAINT GREEN (-5250 3325);
DISPLAY INVISIBLE (-5250 3325);
FORCEADD OFFPAGE..3
R 2
(-3475 3450);
FORCEPROP 2 LAST CDS_LIB mstr_standard
J 0
(-3475 3450);
PAINT MONO (-3475 3450);
DISPLAY INVISIBLE (-3475 3450);
FORCEPROP 1 LAST COMMENT_BODY TRUE
J 2
(-3425 3350);
DISPLAY 1.170213 (-3425 3350);
PAINT GREEN (-3425 3350);
DISPLAY INVISIBLE (-3425 3350);
FORCEPROP 1 LAST OFFPAGE TRUE
J 2
(-3800 3325);
PAINT GREEN (-3800 3325);
DISPLAY INVISIBLE (-3800 3325);
FORCEPROP 2 LAST BOM_COST SM_CONTROLLER
J 2
(-3950 3500);
PAINT MONO (-3950 3500);
DISPLAY INVISIBLE (-3950 3500);
FORCEPROP 2 LAST ROOM BMC
J 2
(-3950 3500);
PAINT MONO (-3950 3500);
DISPLAY INVISIBLE (-3950 3500);
FORCEPROP 2 LAST PATH I70
J 0
(-3425 3525);
DISPLAY 1.021277 (-3425 3525);
PAINT ORANGE (-3425 3525);
DISPLAY INVISIBLE (-3425 3525);
FORCEPROP 2 LAST $XR0 144 
J 0
(-3755 3450);
DISPLAY 0.638298 (-3755 3450);
PAINT MONO (-3755 3450);
FORCEPROP 2 LAST $XR1 176 
J 0
(-3875 3450);
DISPLAY 0.638298 (-3875 3450);
PAINT MONO (-3875 3450);
FORCEPROP 2 LAST $XR2 247 
J 0
(-3995 3450);
DISPLAY 0.638298 (-3995 3450);
PAINT MONO (-3995 3450);
FORCEADD OFFPAGE..1
(-3475 3350);
FORCEPROP 1 LAST COMMENT_BODY TRUE
J 0
(-3350 3250);
DISPLAY 0.872340 (-3350 3250);
PAINT GREEN (-3350 3250);
DISPLAY INVISIBLE (-3350 3250);
FORCEPROP 1 LAST OFFPAGE TRUE
J 0
(-3150 3225);
DISPLAY 0.872340 (-3150 3225);
PAINT GREEN (-3150 3225);
DISPLAY INVISIBLE (-3150 3225);
FORCEPROP 2 LAST CDS_LIB mstr_standard
J 0
(-3475 3350);
PAINT MONO (-3475 3350);
DISPLAY INVISIBLE (-3475 3350);
FORCEPROP 2 LAST PATH I72
J 0
(-3425 3425);
DISPLAY 1.021277 (-3425 3425);
PAINT ORANGE (-3425 3425);
DISPLAY INVISIBLE (-3425 3425);
FORCEPROP 2 LAST $XR0 144 
J 0
(-3757 3350);
DISPLAY 0.638298 (-3757 3350);
PAINT MONO (-3757 3350);
FORCEPROP 2 LAST $XR1 176 
J 0
(-3877 3350);
DISPLAY 0.638298 (-3877 3350);
PAINT MONO (-3877 3350);
FORCEPROP 2 LAST $XR2 247 
J 0
(-3997 3350);
DISPLAY 0.638298 (-3997 3350);
PAINT MONO (-3997 3350);
FORCEADD P3V3_STBY..1
(-6100 2325);
FORCEPROP 3 LASTPIN (-6100 2275) SIG_NAME P3V3_STBY\g
J 0
(-6090 2285);
DISPLAY 0.659574 (-6090 2285);
PAINT MONO (-6090 2285);
DISPLAY INVISIBLE (-6090 2285);
FORCEPROP 1 LAST PATH I73
J 0
(-6055 2327);
DISPLAY 0.340426 (-6055 2327);
PAINT GREEN (-6055 2327);
DISPLAY INVISIBLE (-6055 2327);
FORCEPROP 1 LAST SIZE 1B
J 0
(-6055 2347);
DISPLAY 0.340426 (-6055 2347);
PAINT GREEN (-6055 2347);
DISPLAY INVISIBLE (-6055 2347);
FORCEPROP 1 LAST BODY_TYPE PLUMBING
J 0
(-6145 2282);
DISPLAY 0.340426 (-6145 2282);
PAINT GREEN (-6145 2282);
DISPLAY INVISIBLE (-6145 2282);
FORCEPROP 1 LAST VOLTAGE 3.3V
J 0
(-6145 2282);
DISPLAY 0.340426 (-6145 2282);
PAINT SKYBLUE (-6145 2282);
DISPLAY INVISIBLE (-6145 2282);
FORCEPROP 1 LAST HDL_POWER P3V3_STBY
J 0
(-6400 2200);
DISPLAY 0.872340 (-6400 2200);
PAINT ORANGE (-6400 2200);
DISPLAY INVISIBLE (-6400 2200);
FORCEPROP 2 LAST CDS_LIB mstr_symbols
J 0
(-6100 2325);
PAINT MONO (-6100 2325);
DISPLAY INVISIBLE (-6100 2325);
FORCEADD OFFPAGE..2
(-5200 1650);
FORCEPROP 2 LAST PATH I74
J 0
(-4750 1700);
DISPLAY 1.021277 (-4750 1700);
PAINT ORANGE (-4750 1700);
DISPLAY INVISIBLE (-4750 1700);
FORCEPROP 1 LAST COMMENT_BODY TRUE
J 0
(-5245 1555);
DISPLAY 0.872340 (-5245 1555);
PAINT GREEN (-5245 1555);
DISPLAY INVISIBLE (-5245 1555);
FORCEPROP 2 LAST CDS_LIB mstr_standard
J 0
(-5200 1650);
PAINT ORANGE (-5200 1650);
DISPLAY INVISIBLE (-5200 1650);
FORCEPROP 1 LAST OFFPAGE TRUE
J 0
(-4875 1525);
DISPLAY 0.872340 (-4875 1525);
PAINT GREEN (-4875 1525);
DISPLAY INVISIBLE (-4875 1525);
FORCEPROP 2 LAST $XR3 199 
J 0
(-4771 1650);
DISPLAY 0.638298 (-4771 1650);
PAINT MONO (-4771 1650);
FORCEPROP 2 LAST $XR0 138 
J 0
(-5011 1650);
DISPLAY 0.638298 (-5011 1650);
PAINT MONO (-5011 1650);
FORCEPROP 2 LAST $XR1 159 
J 0
(-4891 1650);
DISPLAY 0.638298 (-4891 1650);
PAINT MONO (-4891 1650);
FORCEPROP 2 LAST $XR2 181 
J 0
(-4771 1650);
DISPLAY 0.638298 (-4771 1650);
PAINT MONO (-4771 1650);
FORCEADD OFFPAGE..4
(-5225 1550);
FORCEPROP 2 LAST PATH I75
J 0
(-5050 1625);
DISPLAY 1.021277 (-5050 1625);
PAINT ORANGE (-5050 1625);
DISPLAY INVISIBLE (-5050 1625);
FORCEPROP 2 LAST CDS_LIB mstr_standard
J 0
(-5225 1550);
PAINT MONO (-5225 1550);
DISPLAY INVISIBLE (-5225 1550);
FORCEPROP 1 LAST OFFPAGE TRUE
J 0
(-4900 1425);
DISPLAY 0.872340 (-4900 1425);
PAINT GREEN (-4900 1425);
DISPLAY INVISIBLE (-4900 1425);
FORCEPROP 1 LAST COMMENT_BODY TRUE
J 0
(-5250 1450);
DISPLAY 0.872340 (-5250 1450);
PAINT GREEN (-5250 1450);
DISPLAY INVISIBLE (-5250 1450);
FORCEPROP 2 LAST $XR0 146 
J 0
(-5009 1550);
DISPLAY 0.638298 (-5009 1550);
PAINT MONO (-5009 1550);
FORCEPROP 2 LAST $XR1 151 
J 0
(-4889 1550);
DISPLAY 0.638298 (-4889 1550);
PAINT MONO (-4889 1550);
FORCEADD PCA9515ADGKR-1-GP..1
(-6475 1625);
FORCEPROP 1 LAST PATH I77
J 0
(-6475 1625);
DISPLAY 0.744681 (-6475 1625);
PAINT GREEN (-6475 1625);
DISPLAY INVISIBLE (-6475 1625);
FORCEPROP 1 LAST CDS_LMAN_SYM_OUTLINE -225,175,225,-175
J 0
(-6475 1625);
DISPLAY 0.468085 (-6475 1625);
PAINT GREEN (-6475 1625);
DISPLAY INVISIBLE (-6475 1625);
FORCEPROP 2 LAST CDS_LIB w_hdl
J 0
(-6475 1625);
PAINT MONO (-6475 1625);
DISPLAY INVISIBLE (-6475 1625);
FORCEPROP 1 LAST PACK_TYPE DISCRET-G5
J 0
(-6475 1625);
DISPLAY 0.744681 (-6475 1625);
PAINT GREEN (-6475 1625);
DISPLAY INVISIBLE (-6475 1625);
FORCEPROP 1 LAST VALUE PCA9515ADGKR-1-GP
J 0
(-6700 1400);
DISPLAY 0.744681 (-6700 1400);
PAINT GREEN (-6700 1400);
FORCEPROP 1 LAST PART_NUMBER 71.09515.F0W
J 0
(-6699 1350);
DISPLAY 0.744681 (-6699 1350);
PAINT GREEN (-6699 1350);
FORCEPROP 1 LAST LOCATION U6W2
J 0
(-6700 1825);
DISPLAY 0.744681 (-6700 1825);
PAINT GREEN (-6700 1825);
FORCEADD GND..1
(-6850 1300);
FORCEPROP 3 LASTPIN (-6850 1350) SIG_NAME GND\g
J 0
(-6840 1360);
DISPLAY 0.659574 (-6840 1360);
PAINT MONO (-6840 1360);
DISPLAY INVISIBLE (-6840 1360);
FORCEPROP 1 LAST PATH I78
J 0
(-6775 1300);
DISPLAY 0.872340 (-6775 1300);
PAINT AQUA (-6775 1300);
DISPLAY INVISIBLE (-6775 1300);
FORCEPROP 2 LAST CDS_LIB mstr_symbols
J 0
(-6850 1300);
PAINT MONO (-6850 1300);
DISPLAY INVISIBLE (-6850 1300);
FORCEPROP 1 LAST SIZE 1B
J 0
(-6775 1250);
DISPLAY 0.872340 (-6775 1250);
PAINT AQUA (-6775 1250);
DISPLAY INVISIBLE (-6775 1250);
FORCEPROP 1 LAST HDL_POWER GND
J 0
(-6850 1450);
DISPLAY 0.872340 (-6850 1450);
PAINT GREEN (-6850 1450);
DISPLAY INVISIBLE (-6850 1450);
FORCEPROP 1 LAST BODY_TYPE PLUMBING
J 0
(-6895 1257);
DISPLAY 0.340426 (-6895 1257);
PAINT GREEN (-6895 1257);
DISPLAY INVISIBLE (-6895 1257);
FORCEPROP 1 LAST VOLTAGE 0.0V
J 0
(-6895 1257);
DISPLAY 0.340426 (-6895 1257);
PAINT GREEN (-6895 1257);
DISPLAY INVISIBLE (-6895 1257);
FORCEADD OFFPAGE..1
(-7575 1650);
FORCEPROP 1 LAST OFFPAGE TRUE
J 0
(-7250 1525);
DISPLAY 0.872340 (-7250 1525);
PAINT GREEN (-7250 1525);
DISPLAY INVISIBLE (-7250 1525);
FORCEPROP 1 LAST COMMENT_BODY TRUE
J 0
(-7450 1550);
DISPLAY 0.872340 (-7450 1550);
PAINT GREEN (-7450 1550);
DISPLAY INVISIBLE (-7450 1550);
FORCEPROP 2 LAST CDS_LIB mstr_standard
J 0
(-7575 1650);
PAINT ORANGE (-7575 1650);
DISPLAY INVISIBLE (-7575 1650);
FORCEPROP 2 LAST PATH I79
J 0
(-7825 1700);
DISPLAY 1.021277 (-7825 1700);
PAINT ORANGE (-7825 1700);
DISPLAY INVISIBLE (-7825 1700);
FORCEPROP 2 LAST $XR0 119 
J 0
(-7827 1650);
DISPLAY 0.638298 (-7827 1650);
PAINT MONO (-7827 1650);
FORCEPROP 2 LAST $XR1 ?
J 0
(-7827 1650);
DISPLAY 0.638298 (-7827 1650);
PAINT MONO (-7827 1650);
FORCEADD RES..2
R 2
(-5250 3425);
FORCEPROP 1 LASTPIN (-5250 3525) $PN 1
J 2
(-5255 3487);
DISPLAY 0.787234 (-5255 3487);
PAINT ORANGE (-5255 3487);
DISPLAY INVISIBLE (-5255 3487);
FORCEPROP 1 LASTPIN (-5250 3325) $PN 2
J 2
(-5255 3335);
DISPLAY 0.787234 (-5255 3335);
PAINT ORANGE (-5255 3335);
DISPLAY INVISIBLE (-5255 3335);
FORCEPROP 0 LAST BOM_COST SM_THERM
J 0
(-5275 3750);
DISPLAY 1.021277 (-5275 3750);
PAINT ORANGE (-5275 3750);
DISPLAY INVISIBLE (-5275 3750);
FORCEPROP 0 LAST ROOM CPU_FANS
J 0
(-5275 3650);
DISPLAY 1.021277 (-5275 3650);
PAINT ORANGE (-5275 3650);
DISPLAY INVISIBLE (-5275 3650);
FORCEPROP 2 LAST CDS_LIB mstr_discrete
J 0
(-5250 3425);
PAINT MONO (-5250 3425);
DISPLAY INVISIBLE (-5250 3425);
FORCEPROP 1 LAST PATH I8
J 2
(-5300 3600);
DISPLAY 0.978723 (-5300 3600);
PAINT WHITE (-5300 3600);
DISPLAY INVISIBLE (-5300 3600);
FORCEPROP 1 LAST PART_NUMBER G21796-072
J 2
(-5290 3300);
DISPLAY 0.617021 (-5290 3300);
PAINT BLUE (-5290 3300);
FORCEPROP 1 LAST TOLERANCE 1%
J 2
(-5295 3450);
DISPLAY 0.617021 (-5295 3450);
PAINT SKYBLUE (-5295 3450);
FORCEPROP 1 LAST PACK_TYPE 0402
J 2
(-5415 3400);
DISPLAY 0.617021 (-5415 3400);
PAINT SKYBLUE (-5415 3400);
FORCEPROP 1 LAST WATTAGE 1/16W
J 2
(-5290 3400);
DISPLAY 0.617021 (-5290 3400);
PAINT SKYBLUE (-5290 3400);
FORCEPROP 1 LAST MATERIAL CHIP
J 2
(-5290 3350);
DISPLAY 0.617021 (-5290 3350);
PAINT SKYBLUE (-5290 3350);
FORCEPROP 1 LAST LOCATION R6W8
J 2
(-5295 3550);
DISPLAY 0.617021 (-5295 3550);
PAINT AQUA (-5295 3550);
FORCEPROP 1 LAST VALUE 4.75K
J 2
(-5295 3500);
DISPLAY 0.617021 (-5295 3500);
PAINT SKYBLUE (-5295 3500);
FORCEADD OFFPAGE..6
(-7575 1600);
FORCEPROP 2 LAST CDS_LIB mstr_standard
J 0
(-7575 1600);
PAINT ORANGE (-7575 1600);
DISPLAY INVISIBLE (-7575 1600);
FORCEPROP 1 LAST COMMENT_BODY TRUE
J 0
(-7475 1525);
DISPLAY 0.872340 (-7475 1525);
PAINT GREEN (-7475 1525);
DISPLAY INVISIBLE (-7475 1525);
FORCEPROP 1 LAST OFFPAGE TRUE
J 0
(-7250 1475);
DISPLAY 0.872340 (-7250 1475);
PAINT GREEN (-7250 1475);
DISPLAY INVISIBLE (-7250 1475);
FORCEPROP 2 LAST PATH I80
J 0
(-7875 1650);
DISPLAY 1.021277 (-7875 1650);
PAINT ORANGE (-7875 1650);
DISPLAY INVISIBLE (-7875 1650);
FORCEPROP 2 LAST $XR1 ?
J 0
(-7885 1600);
DISPLAY 0.638298 (-7885 1600);
PAINT MONO (-7885 1600);
FORCEPROP 2 LAST $XR0 119 
J 0
(-7885 1600);
DISPLAY 0.638298 (-7885 1600);
PAINT MONO (-7885 1600);
FORCEADD CAP..1
(-5900 2075);
FORCEPROP 1 LASTPIN (-5900 2175) $PN 1
J 0
(-5890 2155);
DISPLAY 0.787234 (-5890 2155);
PAINT ORANGE (-5890 2155);
DISPLAY INVISIBLE (-5890 2155);
FORCEPROP 1 LASTPIN (-5900 1975) $PN 2
J 0
(-5890 1955);
DISPLAY 0.787234 (-5890 1955);
PAINT ORANGE (-5890 1955);
DISPLAY INVISIBLE (-5890 1955);
FORCEPROP 2 LAST BOM_COST SM_THERM
J 0
(-5850 2275);
DISPLAY 1.021277 (-5850 2275);
PAINT ORANGE (-5850 2275);
DISPLAY INVISIBLE (-5850 2275);
FORCEPROP 2 LAST ROOM CPUFANS
J 0
(-5850 2225);
DISPLAY 1.021277 (-5850 2225);
PAINT ORANGE (-5850 2225);
DISPLAY INVISIBLE (-5850 2225);
FORCEPROP 1 LAST PATH I81
J 0
(-5850 2225);
DISPLAY 0.978723 (-5850 2225);
PAINT WHITE (-5850 2225);
DISPLAY INVISIBLE (-5850 2225);
FORCEPROP 2 LAST CDS_LIB mstr_discrete
J 0
(-5900 2075);
PAINT MONO (-5900 2075);
DISPLAY INVISIBLE (-5900 2075);
FORCEPROP 1 LAST PACK_TYPE 0402LF
J 0
(-5850 1875);
DISPLAY 0.617021 (-5850 1875);
PAINT SKYBLUE (-5850 1875);
FORCEPROP 1 LAST PART_NUMBER A36096-030
J 0
(-5850 1925);
DISPLAY 0.617021 (-5850 1925);
PAINT BLUE (-5850 1925);
FORCEPROP 1 LAST LOCATION C6W2
J 0
(-5850 2175);
DISPLAY 0.617021 (-5850 2175);
PAINT AQUA (-5850 2175);
FORCEPROP 1 LAST VALUE 0.1UF
J 0
(-5850 2125);
DISPLAY 0.617021 (-5850 2125);
PAINT SKYBLUE (-5850 2125);
FORCEPROP 1 LAST VOLTAGE 16V
J 0
(-5850 2075);
DISPLAY 0.617021 (-5850 2075);
PAINT SKYBLUE (-5850 2075);
FORCEPROP 1 LAST MATERIAL X7R
J 0
(-5850 1975);
DISPLAY 0.617021 (-5850 1975);
PAINT SKYBLUE (-5850 1975);
FORCEPROP 1 LAST TOLERANCE 10%
J 0
(-5850 2025);
DISPLAY 0.617021 (-5850 2025);
PAINT SKYBLUE (-5850 2025);
FORCEADD GND..1
(-5900 1725);
FORCEPROP 3 LASTPIN (-5900 1775) SIG_NAME GND\g
J 0
(-5890 1785);
DISPLAY 0.659574 (-5890 1785);
PAINT MONO (-5890 1785);
DISPLAY INVISIBLE (-5890 1785);
FORCEPROP 2 LAST CDS_LIB mstr_symbols
J 0
(-5900 1725);
PAINT MONO (-5900 1725);
DISPLAY INVISIBLE (-5900 1725);
FORCEPROP 1 LAST PATH I82
J 0
(-5825 1725);
DISPLAY 0.872340 (-5825 1725);
PAINT AQUA (-5825 1725);
DISPLAY INVISIBLE (-5825 1725);
FORCEPROP 1 LAST SIZE 1B
J 0
(-5825 1675);
DISPLAY 0.872340 (-5825 1675);
PAINT AQUA (-5825 1675);
DISPLAY INVISIBLE (-5825 1675);
FORCEPROP 1 LAST HDL_POWER GND
J 0
(-5900 1875);
DISPLAY 0.872340 (-5900 1875);
PAINT GREEN (-5900 1875);
DISPLAY INVISIBLE (-5900 1875);
FORCEPROP 1 LAST BODY_TYPE PLUMBING
J 0
(-5945 1682);
DISPLAY 0.340426 (-5945 1682);
PAINT GREEN (-5945 1682);
DISPLAY INVISIBLE (-5945 1682);
FORCEPROP 1 LAST VOLTAGE 0.0V
J 0
(-5945 1682);
DISPLAY 0.340426 (-5945 1682);
PAINT GREEN (-5945 1682);
DISPLAY INVISIBLE (-5945 1682);
FORCEADD P3V3_STBY..1
(-1775 2550);
FORCEPROP 3 LASTPIN (-1775 2500) SIG_NAME P3V3_STBY\g
J 0
(-1765 2510);
DISPLAY 0.659574 (-1765 2510);
PAINT MONO (-1765 2510);
DISPLAY INVISIBLE (-1765 2510);
FORCEPROP 1 LAST PATH I83
J 0
(-1730 2552);
DISPLAY 0.340426 (-1730 2552);
PAINT GREEN (-1730 2552);
DISPLAY INVISIBLE (-1730 2552);
FORCEPROP 1 LAST HDL_POWER P3V3_STBY
J 0
(-2075 2425);
DISPLAY 0.872340 (-2075 2425);
PAINT ORANGE (-2075 2425);
DISPLAY INVISIBLE (-2075 2425);
FORCEPROP 1 LAST VOLTAGE 3.3V
J 0
(-1820 2507);
DISPLAY 0.340426 (-1820 2507);
PAINT SKYBLUE (-1820 2507);
DISPLAY INVISIBLE (-1820 2507);
FORCEPROP 2 LAST CDS_LIB mstr_symbols
J 0
(-1775 2550);
PAINT ORANGE (-1775 2550);
DISPLAY INVISIBLE (-1775 2550);
FORCEPROP 1 LAST SIZE 1B
J 0
(-1730 2572);
DISPLAY 0.340426 (-1730 2572);
PAINT GREEN (-1730 2572);
DISPLAY INVISIBLE (-1730 2572);
FORCEPROP 1 LAST BODY_TYPE PLUMBING
J 0
(-1820 2507);
DISPLAY 0.340426 (-1820 2507);
PAINT GREEN (-1820 2507);
DISPLAY INVISIBLE (-1820 2507);
FORCEADD OFFPAGE..3
(-325 1750);
FORCEPROP 1 LAST OFFPAGE TRUE
J 0
(0 1625);
DISPLAY 0.872340 (0 1625);
PAINT GREEN (0 1625);
DISPLAY INVISIBLE (0 1625);
FORCEPROP 2 LAST CDS_LIB mstr_standard
J 0
(-325 1750);
PAINT ORANGE (-325 1750);
DISPLAY INVISIBLE (-325 1750);
FORCEPROP 1 LAST COMMENT_BODY TRUE
J 0
(-375 1650);
DISPLAY 0.872340 (-375 1650);
PAINT GREEN (-375 1650);
DISPLAY INVISIBLE (-375 1650);
FORCEPROP 2 LAST PATH I84
J 0
(25 1800);
DISPLAY 1.021277 (25 1800);
PAINT ORANGE (25 1800);
DISPLAY INVISIBLE (25 1800);
FORCEPROP 2 LAST $XR3 138 
J 0
(-111 1714);
DISPLAY 0.638298 (-111 1714);
PAINT MONO (-111 1714);
FORCEPROP 2 LAST $XR4 156 
J 0
(-111 1714);
DISPLAY 0.638298 (-111 1714);
PAINT MONO (-111 1714);
FORCEPROP 2 LAST $XR5 159 
J 0
(-111 1714);
DISPLAY 0.638298 (-111 1714);
PAINT MONO (-111 1714);
FORCEPROP 2 LAST $XR2 111 
J 0
(-111 1714);
DISPLAY 0.638298 (-111 1714);
PAINT MONO (-111 1714);
FORCEPROP 2 LAST $XR0 101 
J 0
(-111 1750);
DISPLAY 0.638298 (-111 1750);
PAINT MONO (-111 1750);
FORCEPROP 2 LAST $XR1 102 
J 0
(-116 1675);
DISPLAY 0.638298 (-116 1675);
PAINT MONO (-116 1675);
FORCEADD CAP_A..1
(-1775 2300);
FORCEPROP 2 LAST CDS_LOCATION C6W3
J 0
(-1725 2400);
DISPLAY 0.617021 (-1725 2400);
PAINT AQUA (-1725 2400);
DISPLAY INVISIBLE (-1725 2400);
FORCEPROP 1 LAST PATH I85
J 0
(-1725 2450);
DISPLAY 0.978723 (-1725 2450);
PAINT WHITE (-1725 2450);
DISPLAY INVISIBLE (-1725 2450);
FORCEPROP 2 LAST CDS_LIB dev_discrete
J 0
(-1775 2300);
PAINT ORANGE (-1775 2300);
DISPLAY INVISIBLE (-1775 2300);
FORCEPROP 2 LAST CDS_SEC 1
J 0
(-1725 2450);
PAINT ORANGE (-1725 2450);
DISPLAY INVISIBLE (-1725 2450);
FORCEPROP 2 LAST ROOM TEMP_SENSORS
J 0
(-1725 2450);
DISPLAY 1.021277 (-1725 2450);
PAINT ORANGE (-1725 2450);
DISPLAY INVISIBLE (-1725 2450);
FORCEPROP 2 LAST SEC 1
J 0
(-1725 2500);
PAINT MONO (-1725 2500);
DISPLAY INVISIBLE (-1725 2500);
FORCEPROP 2 LAST SEC_TYPE 0402V
J 0
(-1725 2500);
DISPLAY 1.021277 (-1725 2500);
PAINT ORANGE (-1725 2500);
DISPLAY INVISIBLE (-1725 2500);
FORCEPROP 2 LAST BOM_COST SM_THERM
J 0
(-1725 2500);
DISPLAY 1.021277 (-1725 2500);
PAINT ORANGE (-1725 2500);
DISPLAY INVISIBLE (-1725 2500);
FORCEPROP 1 LAST VOLTAGE 16V
J 0
(-1725 2300);
DISPLAY 0.617021 (-1725 2300);
PAINT SKYBLUE (-1725 2300);
FORCEPROP 1 LAST VALUE 0.1UF
J 0
(-1725 2350);
DISPLAY 0.617021 (-1725 2350);
PAINT SKYBLUE (-1725 2350);
FORCEPROP 1 LAST LOCATION C6W3
J 0
(-1725 2400);
DISPLAY 0.617021 (-1725 2400);
PAINT AQUA (-1725 2400);
FORCEPROP 1 LAST PACK_TYPE 0402V
J 0
(-1725 2100);
DISPLAY 0.617021 (-1725 2100);
PAINT SKYBLUE (-1725 2100);
FORCEPROP 1 LAST PART_NUMBER A36096-030
J 0
(-1725 2150);
DISPLAY 0.617021 (-1725 2150);
PAINT BLUE (-1725 2150);
FORCEPROP 1 LASTPIN (-1775 2200) $PN 2
J 0
(-1765 2180);
DISPLAY 0.617021 (-1765 2180);
PAINT ORANGE (-1765 2180);
FORCEPROP 1 LASTPIN (-1775 2400) $PN 1
J 0
(-1765 2380);
DISPLAY 0.617021 (-1765 2380);
PAINT ORANGE (-1765 2380);
FORCEPROP 1 LAST MATERIAL X7R
J 0
(-1725 2200);
DISPLAY 0.617021 (-1725 2200);
PAINT SKYBLUE (-1725 2200);
FORCEPROP 1 LAST TOLERANCE 10%
J 0
(-1725 2250);
DISPLAY 0.617021 (-1725 2250);
PAINT SKYBLUE (-1725 2250);
FORCEADD GND..1
(-1775 1975);
FORCEPROP 3 LASTPIN (-1775 2025) SIG_NAME GND\g
J 0
(-1765 2035);
DISPLAY 0.659574 (-1765 2035);
PAINT MONO (-1765 2035);
DISPLAY INVISIBLE (-1765 2035);
FORCEPROP 1 LAST PATH I86
J 0
(-1700 1975);
DISPLAY 0.872340 (-1700 1975);
PAINT AQUA (-1700 1975);
DISPLAY INVISIBLE (-1700 1975);
FORCEPROP 1 LAST BODY_TYPE PLUMBING
J 0
(-1820 1932);
DISPLAY 0.340426 (-1820 1932);
PAINT GREEN (-1820 1932);
DISPLAY INVISIBLE (-1820 1932);
FORCEPROP 1 LAST SIZE 1B
J 0
(-1700 1925);
DISPLAY 0.872340 (-1700 1925);
PAINT AQUA (-1700 1925);
DISPLAY INVISIBLE (-1700 1925);
FORCEPROP 1 LAST VOLTAGE 0.0V
J 0
(-1820 1932);
DISPLAY 0.340426 (-1820 1932);
PAINT SKYBLUE (-1820 1932);
DISPLAY INVISIBLE (-1820 1932);
FORCEPROP 1 LAST HDL_POWER GND
J 0
(-1775 2125);
DISPLAY 0.872340 (-1775 2125);
PAINT GREEN (-1775 2125);
DISPLAY INVISIBLE (-1775 2125);
FORCEPROP 2 LAST CDS_LIB mstr_symbols
J 0
(-1775 1975);
PAINT ORANGE (-1775 1975);
DISPLAY INVISIBLE (-1775 1975);
FORCEADD RES..1
(-1050 1750);
FORCEPROP 2 LAST CDS_LOCATION R6W20
J 0
(-1100 1800);
DISPLAY 0.617021 (-1100 1800);
PAINT AQUA (-1100 1800);
DISPLAY INVISIBLE (-1100 1800);
FORCEPROP 1 LAST PATH I87
J 0
(-1100 1900);
DISPLAY 0.978723 (-1100 1900);
PAINT WHITE (-1100 1900);
DISPLAY INVISIBLE (-1100 1900);
FORCEPROP 1 LASTPIN (-1150 1750) $PN 1
J 0
(-1138 1762);
DISPLAY 0.787234 (-1138 1762);
PAINT ORANGE (-1138 1762);
DISPLAY INVISIBLE (-1138 1762);
FORCEPROP 0 LAST ROOM TEMP_SENSORS
J 0
(-1100 1950);
DISPLAY 1.021277 (-1100 1950);
PAINT ORANGE (-1100 1950);
DISPLAY INVISIBLE (-1100 1950);
FORCEPROP 2 LAST $SEC 1
J 0
(-1100 1950);
PAINT MONO (-1100 1950);
DISPLAY INVISIBLE (-1100 1950);
FORCEPROP 2 LAST CDS_SEC 1
J 0
(-1100 1950);
PAINT MONO (-1100 1950);
DISPLAY INVISIBLE (-1100 1950);
FORCEPROP 0 LAST BOM_COST SM_THERM
J 0
(-1100 2050);
DISPLAY 1.021277 (-1100 2050);
PAINT ORANGE (-1100 2050);
DISPLAY INVISIBLE (-1100 2050);
FORCEPROP 2 LAST CDS_LIB mstr_discrete
J 0
(-1050 1750);
PAINT ORANGE (-1050 1750);
DISPLAY INVISIBLE (-1050 1750);
FORCEPROP 1 LASTPIN (-950 1750) $PN 2
J 0
(-988 1762);
DISPLAY 0.787234 (-988 1762);
PAINT ORANGE (-988 1762);
DISPLAY INVISIBLE (-988 1762);
FORCEPROP 1 LAST WATTAGE 1/16W
J 2
(-1075 1600);
DISPLAY 0.617021 (-1075 1600);
PAINT SKYBLUE (-1075 1600);
FORCEPROP 1 LAST PART_NUMBER G21796-173
J 0
(-1100 1850);
DISPLAY 0.617021 (-1100 1850);
PAINT BLUE (-1100 1850);
FORCEPROP 1 LAST PACK_TYPE 0402
J 0
(-800 1600);
DISPLAY 0.617021 (-800 1600);
PAINT SKYBLUE (-800 1600);
FORCEPROP 1 LAST MATERIAL CHIP
J 0
(-1050 1600);
DISPLAY 0.617021 (-1050 1600);
PAINT SKYBLUE (-1050 1600);
FORCEPROP 1 LAST TOLERANCE 1%
J 0
(-1050 1650);
DISPLAY 0.617021 (-1050 1650);
PAINT SKYBLUE (-1050 1650);
FORCEPROP 1 LAST VALUE 20.0
J 2
(-1075 1650);
DISPLAY 0.617021 (-1075 1650);
PAINT SKYBLUE (-1075 1650);
FORCEPROP 1 LAST LOCATION R6W20
J 0
(-1100 1800);
DISPLAY 0.617021 (-1100 1800);
PAINT AQUA (-1100 1800);
FORCEADD P3V3_STBY..1
(-3000 2500);
FORCEPROP 3 LASTPIN (-3000 2450) SIG_NAME P3V3_STBY\g
J 0
(-2990 2460);
DISPLAY 0.659574 (-2990 2460);
PAINT MONO (-2990 2460);
DISPLAY INVISIBLE (-2990 2460);
FORCEPROP 1 LAST SIZE 1B
J 0
(-2955 2522);
DISPLAY 0.340426 (-2955 2522);
PAINT GREEN (-2955 2522);
DISPLAY INVISIBLE (-2955 2522);
FORCEPROP 1 LAST BODY_TYPE PLUMBING
J 0
(-3045 2457);
DISPLAY 0.340426 (-3045 2457);
PAINT GREEN (-3045 2457);
DISPLAY INVISIBLE (-3045 2457);
FORCEPROP 1 LAST VOLTAGE 3.3V
J 0
(-3045 2457);
DISPLAY 0.340426 (-3045 2457);
PAINT SKYBLUE (-3045 2457);
DISPLAY INVISIBLE (-3045 2457);
FORCEPROP 2 LAST CDS_LIB mstr_symbols
J 0
(-3000 2500);
PAINT MONO (-3000 2500);
DISPLAY INVISIBLE (-3000 2500);
FORCEPROP 1 LAST HDL_POWER P3V3_STBY
J 0
(-3300 2375);
DISPLAY 0.872340 (-3300 2375);
PAINT ORANGE (-3300 2375);
DISPLAY INVISIBLE (-3300 2375);
FORCEPROP 1 LAST PATH I88
J 0
(-2955 2502);
DISPLAY 0.340426 (-2955 2502);
PAINT GREEN (-2955 2502);
DISPLAY INVISIBLE (-2955 2502);
FORCEADD AT24C64..1
(-2200 1850);
FORCEPROP 2 LAST CDS_LOCATION U6W3
J 0
(-2450 2200);
DISPLAY 0.617021 (-2450 2200);
PAINT AQUA (-2450 2200);
DISPLAY INVISIBLE (-2450 2200);
FORCEPROP 2 LAST SEC 1
J 0
(-2450 2250);
DISPLAY 0.680851 (-2450 2250);
PAINT MONO (-2450 2250);
DISPLAY INVISIBLE (-2450 2250);
FORCEPROP 2 LAST BOM_COST SM_THERM
J 0
(-2450 2300);
DISPLAY 1.021277 (-2450 2300);
PAINT ORANGE (-2450 2300);
DISPLAY INVISIBLE (-2450 2300);
FORCEPROP 2 LAST SEC_TYPE SOICLF
J 0
(-2450 2250);
DISPLAY 1.021277 (-2450 2250);
PAINT ORANGE (-2450 2250);
DISPLAY INVISIBLE (-2450 2250);
FORCEPROP 1 LAST PACK_TYPE SOICLF
J 0
(-2450 2250);
DISPLAY 0.957447 (-2450 2250);
PAINT SKYBLUE (-2450 2250);
DISPLAY INVISIBLE (-2450 2250);
FORCEPROP 2 LAST ROOM TEMP_SENSORS
J 0
(-2450 2250);
DISPLAY 1.021277 (-2450 2250);
PAINT ORANGE (-2450 2250);
DISPLAY INVISIBLE (-2450 2250);
FORCEPROP 2 LAST CDS_LIB mstr_memory
J 0
(-2200 1850);
PAINT ORANGE (-2200 1850);
DISPLAY INVISIBLE (-2200 1850);
FORCEPROP 1 LAST PATH I89
J 0
(-2025 2150);
DISPLAY 0.957447 (-2025 2150);
PAINT PURPLE (-2025 2150);
DISPLAY INVISIBLE (-2025 2150);
FORCEPROP 1 LAST POWER_GROUP VCC=P3V3_STBY;GND=GND;
J 0
(-2450 1450);
DISPLAY 0.617021 (-2450 1450);
PAINT ORANGE (-2450 1450);
FORCEPROP 1 LAST LOCATION U6W3
J 0
(-2450 2200);
DISPLAY 0.617021 (-2450 2200);
PAINT AQUA (-2450 2200);
FORCEPROP 1 LAST MATERIAL IC
J 0
(-2450 2150);
DISPLAY 0.617021 (-2450 2150);
PAINT SKYBLUE (-2450 2150);
FORCEPROP 2 LASTPIN (-2500 1700) $PN 7
J 2
(-2510 1710);
DISPLAY 0.617021 (-2510 1710);
PAINT ORANGE (-2510 1710);
FORCEPROP 2 LASTPIN (-1900 1750) $PN 5
J 0
(-1890 1760);
DISPLAY 0.617021 (-1890 1760);
PAINT ORANGE (-1890 1760);
FORCEPROP 2 LASTPIN (-2500 1950) $PN 3
J 2
(-2510 1960);
DISPLAY 0.617021 (-2510 1960);
PAINT ORANGE (-2510 1960);
FORCEPROP 2 LASTPIN (-2500 1750) $PN 6
J 2
(-2510 1760);
DISPLAY 0.617021 (-2510 1760);
PAINT ORANGE (-2510 1760);
FORCEPROP 2 LASTPIN (-2500 1850) $PN 1
J 2
(-2510 1860);
DISPLAY 0.617021 (-2510 1860);
PAINT ORANGE (-2510 1860);
FORCEPROP 2 LASTPIN (-2500 1900) $PN 2
J 2
(-2510 1910);
DISPLAY 0.617021 (-2510 1910);
PAINT ORANGE (-2510 1910);
FORCEPROP 1 LAST PART_NUMBER C47049-001
J 0
(-2450 1500);
DISPLAY 0.617021 (-2450 1500);
PAINT BLUE (-2450 1500);
FORCEADD RES..2
R 2
(-4850 3400);
FORCEPROP 1 LASTPIN (-4850 3500) $PN 1
J 2
(-4855 3462);
DISPLAY 0.787234 (-4855 3462);
PAINT ORANGE (-4855 3462);
DISPLAY INVISIBLE (-4855 3462);
FORCEPROP 1 LASTPIN (-4850 3300) $PN 2
J 2
(-4855 3310);
DISPLAY 0.787234 (-4855 3310);
PAINT ORANGE (-4855 3310);
DISPLAY INVISIBLE (-4855 3310);
FORCEPROP 0 LAST ROOM CPU_FANS
J 0
(-4875 3625);
DISPLAY 1.021277 (-4875 3625);
PAINT ORANGE (-4875 3625);
DISPLAY INVISIBLE (-4875 3625);
FORCEPROP 0 LAST BOM_COST SM_THERM
J 0
(-4875 3725);
DISPLAY 1.021277 (-4875 3725);
PAINT ORANGE (-4875 3725);
DISPLAY INVISIBLE (-4875 3725);
FORCEPROP 2 LAST CDS_LIB mstr_discrete
J 0
(-4850 3400);
PAINT MONO (-4850 3400);
DISPLAY INVISIBLE (-4850 3400);
FORCEPROP 1 LAST PATH I9
J 2
(-4900 3575);
DISPLAY 0.978723 (-4900 3575);
PAINT WHITE (-4900 3575);
DISPLAY INVISIBLE (-4900 3575);
FORCEPROP 1 LAST VALUE 4.75K
J 2
(-4895 3475);
DISPLAY 0.617021 (-4895 3475);
PAINT SKYBLUE (-4895 3475);
FORCEPROP 1 LAST WATTAGE 1/16W
J 2
(-4890 3375);
DISPLAY 0.617021 (-4890 3375);
PAINT SKYBLUE (-4890 3375);
FORCEPROP 1 LAST PART_NUMBER G21796-072
J 2
(-4890 3275);
DISPLAY 0.617021 (-4890 3275);
PAINT BLUE (-4890 3275);
FORCEPROP 1 LAST LOCATION R6W9
J 2
(-4895 3525);
DISPLAY 0.617021 (-4895 3525);
PAINT AQUA (-4895 3525);
FORCEPROP 1 LAST TOLERANCE 1%
J 2
(-4895 3425);
DISPLAY 0.617021 (-4895 3425);
PAINT SKYBLUE (-4895 3425);
FORCEPROP 1 LAST MATERIAL CHIP
J 2
(-4890 3325);
DISPLAY 0.617021 (-4890 3325);
PAINT SKYBLUE (-4890 3325);
FORCEPROP 1 LAST PACK_TYPE 0402
J 2
(-5015 3375);
DISPLAY 0.617021 (-5015 3375);
PAINT SKYBLUE (-5015 3375);
FORCEADD RES..2
(-3000 2200);
FORCEPROP 2 LAST CDS_LOCATION R6W21
J 0
(-2955 2325);
DISPLAY 0.617021 (-2955 2325);
PAINT AQUA (-2955 2325);
DISPLAY INVISIBLE (-2955 2325);
FORCEPROP 2 LAST ROOM TEMP_SENSORS
J 0
(-2950 2375);
DISPLAY 1.021277 (-2950 2375);
PAINT ORANGE (-2950 2375);
DISPLAY INVISIBLE (-2950 2375);
FORCEPROP 0 LAST SEC 1
J 0
(-2950 2375);
DISPLAY 0.680851 (-2950 2375);
PAINT MONO (-2950 2375);
DISPLAY INVISIBLE (-2950 2375);
FORCEPROP 2 LAST BOM_COST SM_THERM
J 0
(-2950 2425);
DISPLAY 1.021277 (-2950 2425);
PAINT ORANGE (-2950 2425);
DISPLAY INVISIBLE (-2950 2425);
FORCEPROP 2 LAST SEC_TYPE 0402
J 0
(-2950 2425);
DISPLAY 1.021277 (-2950 2425);
PAINT ORANGE (-2950 2425);
DISPLAY INVISIBLE (-2950 2425);
FORCEPROP 2 LAST CDS_LIB mstr_discrete
J 0
(-3000 2200);
PAINT ORANGE (-3000 2200);
DISPLAY INVISIBLE (-3000 2200);
FORCEPROP 1 LAST PATH I90
J 0
(-2950 2375);
DISPLAY 0.978723 (-2950 2375);
PAINT WHITE (-2950 2375);
DISPLAY INVISIBLE (-2950 2375);
FORCEPROP 1 LAST LOCATION R6W21
J 0
(-2955 2325);
DISPLAY 0.617021 (-2955 2325);
PAINT AQUA (-2955 2325);
FORCEPROP 1 LAST VALUE 1.00K
J 0
(-2955 2275);
DISPLAY 0.617021 (-2955 2275);
PAINT SKYBLUE (-2955 2275);
FORCEPROP 1 LAST TOLERANCE 1%
J 0
(-2955 2225);
DISPLAY 0.617021 (-2955 2225);
PAINT SKYBLUE (-2955 2225);
FORCEPROP 1 LAST WATTAGE 1/16W
J 0
(-2960 2175);
DISPLAY 0.617021 (-2960 2175);
PAINT SKYBLUE (-2960 2175);
FORCEPROP 1 LASTPIN (-3000 2300) $PN 1
J 0
(-2995 2262);
DISPLAY 0.617021 (-2995 2262);
PAINT ORANGE (-2995 2262);
FORCEPROP 1 LAST MATERIAL CHIP
J 0
(-2960 2125);
DISPLAY 0.617021 (-2960 2125);
PAINT SKYBLUE (-2960 2125);
FORCEPROP 1 LASTPIN (-3000 2100) $PN 2
J 0
(-2995 2110);
DISPLAY 0.617021 (-2995 2110);
PAINT ORANGE (-2995 2110);
FORCEPROP 1 LAST PART_NUMBER G21796-026
J 0
(-2960 2075);
DISPLAY 0.617021 (-2960 2075);
PAINT BLUE (-2960 2075);
FORCEPROP 1 LAST PACK_TYPE 0402
J 0
(-2960 2025);
DISPLAY 0.617021 (-2960 2025);
PAINT SKYBLUE (-2960 2025);
FORCEADD GND..1
(-2575 1275);
FORCEPROP 3 LASTPIN (-2575 1325) SIG_NAME GND\g
J 0
(-2565 1335);
DISPLAY 0.659574 (-2565 1335);
PAINT MONO (-2565 1335);
DISPLAY INVISIBLE (-2565 1335);
FORCEPROP 1 LAST SIZE 1B
J 0
(-2500 1225);
DISPLAY 0.872340 (-2500 1225);
PAINT AQUA (-2500 1225);
DISPLAY INVISIBLE (-2500 1225);
FORCEPROP 2 LAST CDS_LIB mstr_symbols
J 0
(-2575 1275);
PAINT ORANGE (-2575 1275);
DISPLAY INVISIBLE (-2575 1275);
FORCEPROP 1 LAST HDL_POWER GND
J 0
(-2575 1425);
DISPLAY 0.872340 (-2575 1425);
PAINT GREEN (-2575 1425);
DISPLAY INVISIBLE (-2575 1425);
FORCEPROP 1 LAST VOLTAGE 0.0V
J 0
(-2620 1232);
DISPLAY 0.340426 (-2620 1232);
PAINT SKYBLUE (-2620 1232);
DISPLAY INVISIBLE (-2620 1232);
FORCEPROP 1 LAST BODY_TYPE PLUMBING
J 0
(-2620 1232);
DISPLAY 0.340426 (-2620 1232);
PAINT GREEN (-2620 1232);
DISPLAY INVISIBLE (-2620 1232);
FORCEPROP 1 LAST PATH I91
J 0
(-2500 1275);
DISPLAY 0.872340 (-2500 1275);
PAINT AQUA (-2500 1275);
DISPLAY INVISIBLE (-2500 1275);
FORCEADD RES..2
(-3000 1525);
FORCEPROP 2 LAST CDS_LOCATION R6W23
J 0
(-2955 1650);
DISPLAY 0.617021 (-2955 1650);
PAINT AQUA (-2955 1650);
DISPLAY INVISIBLE (-2955 1650);
FORCEPROP 2 LAST SEC_TYPE 0402
J 0
(-2950 1750);
DISPLAY 1.021277 (-2950 1750);
PAINT ORANGE (-2950 1750);
DISPLAY INVISIBLE (-2950 1750);
FORCEPROP 2 LAST BOM_COST SM_THERM
J 0
(-2950 1750);
DISPLAY 1.021277 (-2950 1750);
PAINT ORANGE (-2950 1750);
DISPLAY INVISIBLE (-2950 1750);
FORCEPROP 2 LAST ROOM TEMP_SENSORS
J 0
(-2950 1700);
DISPLAY 1.021277 (-2950 1700);
PAINT ORANGE (-2950 1700);
DISPLAY INVISIBLE (-2950 1700);
FORCEPROP 0 LAST SEC 1
J 0
(-2950 1700);
DISPLAY 0.680851 (-2950 1700);
PAINT MONO (-2950 1700);
DISPLAY INVISIBLE (-2950 1700);
FORCEPROP 2 LAST CDS_LIB mstr_discrete
J 0
(-3000 1525);
PAINT ORANGE (-3000 1525);
DISPLAY INVISIBLE (-3000 1525);
FORCEPROP 1 LAST PATH I92
J 0
(-2950 1700);
DISPLAY 0.978723 (-2950 1700);
PAINT WHITE (-2950 1700);
DISPLAY INVISIBLE (-2950 1700);
FORCEPROP 1 LASTPIN (-3000 1425) $PN 2
J 0
(-2995 1435);
DISPLAY 0.617021 (-2995 1435);
PAINT ORANGE (-2995 1435);
FORCEPROP 1 LAST TOLERANCE 1%
J 0
(-2955 1550);
DISPLAY 0.617021 (-2955 1550);
PAINT SKYBLUE (-2955 1550);
FORCEPROP 1 LAST VALUE 1.00K
J 0
(-2955 1600);
DISPLAY 0.617021 (-2955 1600);
PAINT SKYBLUE (-2955 1600);
FORCEPROP 1 LASTPIN (-3000 1625) $PN 1
J 0
(-2995 1587);
DISPLAY 0.617021 (-2995 1587);
PAINT ORANGE (-2995 1587);
FORCEPROP 1 LAST PACK_TYPE 0402
J 0
(-2960 1350);
DISPLAY 0.617021 (-2960 1350);
PAINT SKYBLUE (-2960 1350);
FORCEPROP 1 LAST MATERIAL CHIP
J 0
(-2960 1450);
DISPLAY 0.617021 (-2960 1450);
PAINT SKYBLUE (-2960 1450);
FORCEPROP 1 LAST WATTAGE 1/16W
J 0
(-2960 1500);
DISPLAY 0.617021 (-2960 1500);
PAINT SKYBLUE (-2960 1500);
FORCEPROP 1 LAST PART_NUMBER G21796-026
J 0
(-2960 1400);
DISPLAY 0.617021 (-2960 1400);
PAINT BLUE (-2960 1400);
FORCEPROP 1 LAST LOCATION R6W23
J 0
(-2955 1650);
DISPLAY 0.617021 (-2955 1650);
PAINT AQUA (-2955 1650);
FORCEADD GND..1
(-3000 1275);
FORCEPROP 3 LASTPIN (-3000 1325) SIG_NAME GND\g
J 0
(-2990 1335);
DISPLAY 0.659574 (-2990 1335);
PAINT MONO (-2990 1335);
DISPLAY INVISIBLE (-2990 1335);
FORCEPROP 1 LAST HDL_POWER GND
J 0
(-3000 1425);
DISPLAY 0.872340 (-3000 1425);
PAINT GREEN (-3000 1425);
DISPLAY INVISIBLE (-3000 1425);
FORCEPROP 2 LAST CDS_LIB mstr_symbols
J 0
(-3000 1275);
PAINT ORANGE (-3000 1275);
DISPLAY INVISIBLE (-3000 1275);
FORCEPROP 1 LAST SIZE 1B
J 0
(-2925 1225);
DISPLAY 0.872340 (-2925 1225);
PAINT AQUA (-2925 1225);
DISPLAY INVISIBLE (-2925 1225);
FORCEPROP 1 LAST VOLTAGE 0.0V
J 0
(-3045 1232);
DISPLAY 0.340426 (-3045 1232);
PAINT SKYBLUE (-3045 1232);
DISPLAY INVISIBLE (-3045 1232);
FORCEPROP 1 LAST BODY_TYPE PLUMBING
J 0
(-3045 1232);
DISPLAY 0.340426 (-3045 1232);
PAINT GREEN (-3045 1232);
DISPLAY INVISIBLE (-3045 1232);
FORCEPROP 1 LAST PATH I93
J 0
(-2925 1275);
DISPLAY 0.872340 (-2925 1275);
PAINT AQUA (-2925 1275);
DISPLAY INVISIBLE (-2925 1275);
FORCEADD RES..1
(-3425 1750);
FORCEPROP 2 LAST CDS_LOCATION R6W22
J 0
(-3475 1800);
DISPLAY 0.617021 (-3475 1800);
PAINT AQUA (-3475 1800);
DISPLAY INVISIBLE (-3475 1800);
FORCEPROP 1 LAST PATH I94
J 0
(-3475 1900);
DISPLAY 0.978723 (-3475 1900);
PAINT WHITE (-3475 1900);
DISPLAY INVISIBLE (-3475 1900);
FORCEPROP 0 LAST SEC 1
J 0
(-3475 1900);
DISPLAY 0.680851 (-3475 1900);
PAINT MONO (-3475 1900);
DISPLAY INVISIBLE (-3475 1900);
FORCEPROP 2 LAST CDS_LIB mstr_discrete
J 0
(-3425 1750);
PAINT ORANGE (-3425 1750);
DISPLAY INVISIBLE (-3425 1750);
FORCEPROP 0 LAST ROOM TEMP_SENSORS
J 0
(-3475 1950);
DISPLAY 1.021277 (-3475 1950);
PAINT ORANGE (-3475 1950);
DISPLAY INVISIBLE (-3475 1950);
FORCEPROP 2 LAST SEC_TYPE 0402
J 0
(-3475 1950);
DISPLAY 1.021277 (-3475 1950);
PAINT ORANGE (-3475 1950);
DISPLAY INVISIBLE (-3475 1950);
FORCEPROP 0 LAST BOM_COST SM_THERM
J 0
(-3475 2050);
DISPLAY 1.021277 (-3475 2050);
PAINT ORANGE (-3475 2050);
DISPLAY INVISIBLE (-3475 2050);
FORCEPROP 1 LAST PART_NUMBER G21796-173
J 0
(-3475 1850);
DISPLAY 0.617021 (-3475 1850);
PAINT BLUE (-3475 1850);
FORCEPROP 1 LASTPIN (-3525 1750) $PN 1
J 0
(-3513 1762);
DISPLAY 0.617021 (-3513 1762);
PAINT ORANGE (-3513 1762);
FORCEPROP 1 LASTPIN (-3325 1750) $PN 2
J 0
(-3363 1762);
DISPLAY 0.617021 (-3363 1762);
PAINT ORANGE (-3363 1762);
FORCEPROP 1 LAST TOLERANCE 1%
J 0
(-3425 1650);
DISPLAY 0.617021 (-3425 1650);
PAINT SKYBLUE (-3425 1650);
FORCEPROP 1 LAST PACK_TYPE 0402
J 0
(-3175 1600);
DISPLAY 0.617021 (-3175 1600);
PAINT SKYBLUE (-3175 1600);
FORCEPROP 1 LAST LOCATION R6W22
J 0
(-3475 1800);
DISPLAY 0.617021 (-3475 1800);
PAINT AQUA (-3475 1800);
FORCEPROP 1 LAST VALUE 20.0
J 2
(-3450 1650);
DISPLAY 0.617021 (-3450 1650);
PAINT SKYBLUE (-3450 1650);
FORCEPROP 1 LAST WATTAGE 1/16W
J 2
(-3450 1600);
DISPLAY 0.617021 (-3450 1600);
PAINT SKYBLUE (-3450 1600);
FORCEPROP 1 LAST MATERIAL CHIP
J 0
(-3425 1600);
DISPLAY 0.617021 (-3425 1600);
PAINT SKYBLUE (-3425 1600);
FORCEADD OFFPAGE..1
(-4150 1750);
FORCEPROP 1 LAST OFFPAGE TRUE
J 0
(-3825 1625);
DISPLAY 0.872340 (-3825 1625);
PAINT GREEN (-3825 1625);
DISPLAY INVISIBLE (-3825 1625);
FORCEPROP 1 LAST COMMENT_BODY TRUE
J 0
(-4025 1650);
DISPLAY 0.872340 (-4025 1650);
PAINT GREEN (-4025 1650);
DISPLAY INVISIBLE (-4025 1650);
FORCEPROP 2 LAST CDS_LIB mstr_standard
J 0
(-4150 1750);
PAINT ORANGE (-4150 1750);
DISPLAY INVISIBLE (-4150 1750);
FORCEPROP 2 LAST PATH I95
J 0
(-4400 1800);
DISPLAY 1.021277 (-4400 1800);
PAINT ORANGE (-4400 1800);
DISPLAY INVISIBLE (-4400 1800);
FORCEPROP 2 LAST $XR3 102 
J 0
(-4642 1750);
DISPLAY 0.638298 (-4642 1750);
PAINT MONO (-4642 1750);
FORCEPROP 2 LAST $XR4 111 
J 0
(-4642 1750);
DISPLAY 0.638298 (-4642 1750);
PAINT MONO (-4642 1750);
FORCEPROP 2 LAST $XR5 156 
J 0
(-4642 1750);
DISPLAY 0.638298 (-4642 1750);
PAINT MONO (-4642 1750);
FORCEPROP 2 LAST $XR2 101 
J 0
(-4642 1750);
DISPLAY 0.638298 (-4642 1750);
PAINT MONO (-4642 1750);
FORCEPROP 2 LAST $XR1 159 
J 0
(-4522 1750);
DISPLAY 0.638298 (-4522 1750);
PAINT MONO (-4522 1750);
FORCEPROP 2 LAST $XR0 138 
J 0
(-4402 1750);
DISPLAY 0.638298 (-4402 1750);
PAINT MONO (-4402 1750);
FORCEADD OFFPAGE..3
(-5225 1600);
FORCEPROP 1 LAST COMMENT_BODY TRUE
J 0
(-5275 1500);
DISPLAY 0.872340 (-5275 1500);
PAINT GREEN (-5275 1500);
DISPLAY INVISIBLE (-5275 1500);
FORCEPROP 1 LAST OFFPAGE TRUE
J 0
(-4900 1475);
DISPLAY 0.872340 (-4900 1475);
PAINT GREEN (-4900 1475);
DISPLAY INVISIBLE (-4900 1475);
FORCEPROP 2 LAST CDS_LIB mstr_standard
J 0
(-5225 1600);
PAINT ORANGE (-5225 1600);
DISPLAY INVISIBLE (-5225 1600);
FORCEPROP 2 LAST PATH I96
J 0
(-4750 1650);
DISPLAY 1.021277 (-4750 1650);
PAINT ORANGE (-4750 1650);
DISPLAY INVISIBLE (-4750 1650);
FORCEPROP 2 LAST $XR0 138 
J 0
(-5011 1600);
DISPLAY 0.638298 (-5011 1600);
PAINT MONO (-5011 1600);
FORCEPROP 2 LAST $XR3 199 
J 0
(-4771 1600);
DISPLAY 0.638298 (-4771 1600);
PAINT MONO (-4771 1600);
FORCEPROP 2 LAST $XR1 159 
J 0
(-4891 1600);
DISPLAY 0.638298 (-4891 1600);
PAINT MONO (-4891 1600);
FORCEPROP 2 LAST $XR2 181 
J 0
(-4771 1600);
DISPLAY 0.638298 (-4771 1600);
PAINT MONO (-4771 1600);
FORCEADD PCA9555PWRG4-GP..1
(-2400 3600);
FORCEPROP 1 LAST PACK_TYPE DISCRET-G5
J 0
(-2400 3600);
DISPLAY 0.744681 (-2400 3600);
PAINT GREEN (-2400 3600);
DISPLAY INVISIBLE (-2400 3600);
FORCEPROP 2 LAST CDS_LIB w_hdl
J 0
(-2400 3600);
PAINT MONO (-2400 3600);
DISPLAY INVISIBLE (-2400 3600);
FORCEPROP 1 LAST PATH I97
J 0
(-2400 3600);
DISPLAY 0.744681 (-2400 3600);
PAINT GREEN (-2400 3600);
DISPLAY INVISIBLE (-2400 3600);
FORCEPROP 1 LAST CDS_LMAN_SYM_OUTLINE -200,550,200,-550
J 0
(-2400 3600);
DISPLAY 0.468085 (-2400 3600);
PAINT GREEN (-2400 3600);
DISPLAY INVISIBLE (-2400 3600);
FORCEPROP 1 LAST LOCATION U6W1
J 0
(-2600 4156);
DISPLAY 0.744681 (-2600 4156);
PAINT GREEN (-2600 4156);
FORCEPROP 1 LAST VALUE PCA9555PWRG4-GP
J 0
(-2599 3016);
DISPLAY 0.744681 (-2599 3016);
PAINT GREEN (-2599 3016);
FORCEPROP 1 LAST PART_NUMBER 71.09555.B0W
J 0
(-2599 2980);
DISPLAY 0.744681 (-2599 2980);
PAINT GREEN (-2599 2980);
FORCEADD CAD_NOTE..1
(-3925 1250);
FORCEPROP 2 LAST CDS_LIB mstr_symbols
J 0
(-3925 1250);
PAINT ORANGE (-3925 1250);
DISPLAY INVISIBLE (-3925 1250);
FORCEPROP 1 LAST COMMENT_BODY TRUE
J 0
(-3900 1350);
DISPLAY 0.978723 (-3900 1350);
PAINT ORANGE (-3900 1350);
DISPLAY INVISIBLE (-3900 1350);
FORCEPROP 0 LAST L1 PLACE SERIES RESISTORS ON SMB_HOST_STBY_LVC3_SDA/SCL NETS CLOSE TO AT24C64
J 0
(-4075 1075);
DISPLAY 0.808511 (-4075 1075);
PAINT ORANGE (-4075 1075);
FORCEADD DNS..2
(-5645 4045);
PAINT RED (-5645 4045);
FORCEPROP 2 LAST CDS_LIB mstr_misc
J 0
(-5645 4045);
PAINT MONO (-5645 4045);
DISPLAY INVISIBLE (-5645 4045);
FORCEPROP 1 LAST COMMENT_BODY TRUE
R 1
J 0
(-5570 3820);
DISPLAY 0.872340 (-5570 3820);
PAINT GREEN (-5570 3820);
DISPLAY INVISIBLE (-5570 3820);
FORCEADD DNS..2
(-4845 4045);
PAINT RED (-4845 4045);
FORCEPROP 2 LAST CDS_LIB mstr_misc
J 0
(-4845 4045);
PAINT MONO (-4845 4045);
DISPLAY INVISIBLE (-4845 4045);
FORCEPROP 1 LAST COMMENT_BODY TRUE
R 1
J 0
(-4770 3820);
DISPLAY 0.872340 (-4770 3820);
PAINT GREEN (-4770 3820);
DISPLAY INVISIBLE (-4770 3820);
FORCEADD CAD_NOTE..1
(-1400 2575);
FORCEPROP 1 LAST COMMENT_BODY TRUE
J 0
(-1375 2675);
DISPLAY 0.978723 (-1375 2675);
PAINT ORANGE (-1375 2675);
DISPLAY INVISIBLE (-1375 2675);
FORCEPROP 2 LAST CDS_LIB mstr_symbols
J 0
(-1400 2575);
PAINT ORANGE (-1400 2575);
DISPLAY INVISIBLE (-1400 2575);
FORCEPROP 0 LAST L1 PLACE CAP CLOSE
J 0
(-1550 2450);
DISPLAY 1.021277 (-1550 2450);
PAINT ORANGE (-1550 2450);
FORCEPROP 0 LAST L2 TO AT24C64
J 0
(-1550 2375);
DISPLAY 1.021277 (-1550 2375);
PAINT ORANGE (-1550 2375);
FORCEADD DNS..2
(-7120 3795);
PAINT RED (-7120 3795);
FORCEPROP 1 LAST COMMENT_BODY TRUE
R 1
J 0
(-7045 3570);
DISPLAY 0.872340 (-7045 3570);
PAINT GREEN (-7045 3570);
DISPLAY INVISIBLE (-7045 3570);
FORCEPROP 2 LAST CDS_LIB mstr_misc
J 0
(-7120 3795);
PAINT MONO (-7120 3795);
DISPLAY INVISIBLE (-7120 3795);
FORCEADD DESIGN_NOTE..1
(-1625 1250);
FORCEPROP 1 LAST COMMENT_BODY TRUE
J 0
(-1600 1350);
DISPLAY 0.978723 (-1600 1350);
PAINT ORANGE (-1600 1350);
DISPLAY INVISIBLE (-1600 1350);
FORCEPROP 2 LAST CDS_LIB mstr_symbols
J 0
(-1625 1250);
PAINT ORANGE (-1625 1250);
DISPLAY INVISIBLE (-1625 1250);
FORCEADD DNS..2
(-5245 4045);
PAINT RED (-5245 4045);
FORCEPROP 2 LAST CDS_LIB mstr_misc
J 0
(-5245 4045);
PAINT MONO (-5245 4045);
DISPLAY INVISIBLE (-5245 4045);
FORCEPROP 1 LAST COMMENT_BODY TRUE
R 1
J 0
(-5170 3820);
DISPLAY 0.872340 (-5170 3820);
PAINT GREEN (-5170 3820);
DISPLAY INVISIBLE (-5170 3820);
FORCEADD DNS..2
(-6795 3795);
PAINT RED (-6795 3795);
FORCEPROP 2 LAST CDS_LIB mstr_misc
J 0
(-6795 3795);
PAINT MONO (-6795 3795);
DISPLAY INVISIBLE (-6795 3795);
FORCEPROP 1 LAST COMMENT_BODY TRUE
R 1
J 0
(-6720 3570);
DISPLAY 0.872340 (-6720 3570);
PAINT GREEN (-6720 3570);
DISPLAY INVISIBLE (-6720 3570);
FORCEADD INTEL_CORP_BPAGE..1
(0 0);
FORCEPROP 1 LAST CDS_CON_LAST_MODIFIED Tue Dec 01 13:44:27 2015
J 0
(-1425 325);
PAINT ORANGE (-1425 325);
DISPLAY INVISIBLE (-1425 325);
FORCEPROP 1 LAST CUSTOM_TXT_CDS <CURRENT_DESIGN_SHEET> OF <TOTAL_DESIGN_SHEETS>
J 0
(-500 25);
PAINT ORANGE (-500 25);
FORCEPROP 1 LAST CUSTOM_TXT_CDS <CON_LAST_MODIFIED>
J 0
(-1925 350);
PAINT ORANGE (-1925 350);
FORCEPROP 2 LAST CUSTOM_TXT_CDS <XR_PAGE_TITLE>
J 0
(-7890 5250);
DISPLAY 0.638298 (-7890 5250);
PAINT PINK (-7890 5250);
DISPLAY INVISIBLE (-7890 5250);
FORCEPROP 2 LAST CDS_XR_PAGE_TITLE CR-247 : @BASEBOARD_FAB2_LIB.BASEBOARD_FAB2(SCH_1):PAGE247
J 0
(-7890 5250);
DISPLAY 0.638298 (-7890 5250);
PAINT PINK (-7890 5250);
DISPLAY INVISIBLE (-7890 5250);
FORCEPROP 2 LAST PAGE_BORDER TRUE
J 0
(-7890 5250);
DISPLAY 0.638298 (-7890 5250);
PAINT PINK (-7890 5250);
DISPLAY INVISIBLE (-7890 5250);
FORCEPROP 2 LAST CDS_LIB mstr_symbols
J 0
(0 0);
PAINT MONO (0 0);
DISPLAY INVISIBLE (0 0);
FORCEPROP 1 LAST COMMENT_BODY TRUE
J 0
(12 12);
DISPLAY 0.468085 (12 12);
PAINT GREEN (12 12);
DISPLAY INVISIBLE (12 12);
FORCEPROP 1 LAST SCH_REV 0.1
J 0
(-250 150);
DISPLAY 1.170213 (-250 150);
PAINT GREEN (-250 150);
FORCEPROP 1 LAST SCH_DEPT UNKNOWN
J 1
(-4450 100);
DISPLAY 1.255319 (-4450 100);
PAINT ORANGE (-4450 100);
FORCEPROP 1 LAST SCH_ADDRESS2 P.O. BOX 58119
J 0
(-3975 75);
DISPLAY 0.872340 (-3975 75);
PAINT GREEN (-3975 75);
FORCEPROP 1 LAST SCH_ADDRESS3 Santa Clara, CA 95052-8119
J 0
(-3975 25);
DISPLAY 0.872340 (-3975 25);
PAINT GREEN (-3975 25);
FORCEPROP 1 LAST SCH_NUMBER 000000-000
J 0
(-1300 150);
DISPLAY 1.702128 (-1300 150);
PAINT GREEN (-1300 150);
FORCEPROP 1 LAST SCH_ADDRESS1 2200 Mission College Blvd.
J 0
(-3975 125);
DISPLAY 0.872340 (-3975 125);
PAINT GREEN (-3975 125);
FORCEPROP 1 LAST SCH_TITLE Remap USB3.0 as debug port
J 0
(-7950 50);
DISPLAY 2.468085 (-7950 50);
PAINT ORANGE (-7950 50);
WIRE 16 -1 (-7375 4275)(-7375 4100);
WIRE 16 -1 (-7150 4100)(-7375 4100);
WIRE 16 -1 (-7375 4100)(-7375 3900);
WIRE 16 -1 (-6850 4100)(-7150 4100);
WIRE 16 -1 (-7150 3900)(-7150 4100);
WIRE 16 -1 (-6850 3900)(-6850 4100);
WIRE 16 -1 (-4850 3200)(-4850 3300);
WIRE 16 -1 (-3600 3850)(-3600 3800);
WIRE 16 -1 (-1900 3050)(-1900 3150);
WIRE 16 -1 (-2050 3150)(-1900 3150);
WIRE 16 -1 (-5650 3225)(-5650 3325);
WIRE 16 -1 (-5650 4250)(-5650 4275);
WIRE 16 -1 (-5650 4150)(-5650 4250);
WIRE 16 -1 (-5250 4250)(-5650 4250);
WIRE 16 -1 (-4850 4250)(-5250 4250);
WIRE 16 -1 (-5250 4150)(-5250 4250);
WIRE 16 -1 (-4850 4150)(-4850 4250);
WIRE 16 -1 (-5250 3225)(-5250 3325);
WIRE 16 -1 (-6100 2175)(-6100 2275);
WIRE 16 -1 (-6100 1700)(-6100 2175);
WIRE 16 -1 (-5900 2175)(-6100 2175);
WIRE 16 -1 (-6850 1550)(-6850 1350);
WIRE 16 -1 (-5900 1975)(-5900 1775);
WIRE 16 -1 (-1775 2200)(-1775 2025);
WIRE 16 -1 (-3000 2450)(-3000 2300);
WIRE 16 -1 (-2575 1325)(-2575 1850);
WIRE 16 -1 (-2575 1850)(-2575 1900);
WIRE 16 -1 (-2575 1850)(-2500 1850);
WIRE 16 -1 (-2575 1900)(-2500 1900);
WIRE 16 -1 (-3000 1325)(-3000 1425);
WIRE 16 -1 (-1775 2500)(-1775 2400);
WIRE 16 -1 (-3600 4275)(-3600 4200);
WIRE 16 -1 (-3600 4200)(-2750 4200);
WIRE 16 -1 (-3600 4200)(-3600 4050);
WIRE 16 -1 (-2750 4200)(-2750 4050);
WIRE 16 -1 (-2750 3850)(-3175 3850);
FORCEPROP 2 LAST SIG_NAME PCA9555_A2
J 0
(-3185 3860);
DISPLAY 0.680851 (-3185 3860);
PAINT ORANGE (-3185 3860);
FORCEPROP 2 LASTPROP $XR0 247 
J 0
(-3301 3850);
DISPLAY 0.638298 (-3301 3850);
PAINT MONO (-3301 3850);
WIRE 3 2175 (-4650 500)(-25 500);
WIRE 3 2175 (-25 2775)(-25 500);
WIRE 3 2175 (-4650 2775)(-4650 500);
WIRE 3 2175 (-4650 2775)(-25 2775);
WIRE 3 2175 (-7825 4700)(-775 4700);
WIRE 3 2175 (-775 4700)(-775 2900);
WIRE 3 2175 (-7825 4700)(-7825 2900);
WIRE 3 2175 (-7825 2900)(-775 2900);
WIRE 16 -1 (-2050 3800)(-1575 3800);
FORCEPROP 2 LAST SIG_NAME LED_POSTCODE_5_R
J 2
(-1625 3810);
DISPLAY 0.617021 (-1625 3810);
PAINT ORANGE (-1625 3810);
WIRE 3 2175 (-7925 2450)(-4700 2450);
WIRE 3 2175 (-4700 2450)(-4700 1200);
WIRE 3 2175 (-7925 2450)(-7925 1200);
WIRE 3 2175 (-7925 1200)(-4700 1200);
WIRE 16 -1 (-6100 1650)(-5250 1650);
FORCEPROP 0 LAST CDS_PHYS_NET_NAME SMB_BMC_PMBUS_STBY_LVC3_SCL
J 0
(-5325 1689);
PAINT MONO (-5325 1689);
DISPLAY INVISIBLE (-5325 1689);
FORCEPROP 2 LAST SIG_NAME SMB_BMC_PMBUS_STBY_LVC3_SCL
J 2
(-5325 1660);
DISPLAY 0.617021 (-5325 1660);
PAINT ORANGE (-5325 1660);
WIRE 16 -1 (-2050 3700)(-1575 3700);
FORCEPROP 2 LAST SIG_NAME LED_POSTCODE_7_R
J 2
(-1625 3710);
DISPLAY 0.617021 (-1625 3710);
PAINT ORANGE (-1625 3710);
WIRE 16 -1 (-2750 3250)(-3425 3250);
FORCEPROP 2 LAST SIG_NAME PCA9555_INT_N
J 0
(-3260 3260);
DISPLAY 0.680851 (-3260 3260);
PAINT ORANGE (-3260 3260);
FORCEPROP 2 LASTPROP $XR0 247 
J 0
(-3521 3250);
DISPLAY 0.638298 (-3521 3250);
PAINT MONO (-3521 3250);
WIRE 16 -1 (-2750 3800)(-3175 3800);
FORCEPROP 2 LAST SIG_NAME PCA9555_A1
J 0
(-3185 3810);
DISPLAY 0.680851 (-3185 3810);
PAINT ORANGE (-3185 3810);
FORCEPROP 2 LASTPROP $XR0 247 
J 0
(-3296 3800);
DISPLAY 0.638298 (-3296 3800);
PAINT MONO (-3296 3800);
WIRE 16 -1 (-2050 4050)(-1575 4050);
FORCEPROP 2 LAST SIG_NAME LED_POSTCODE_0_R
J 0
(-2025 4060);
DISPLAY 0.617021 (-2025 4060);
PAINT ORANGE (-2025 4060);
WIRE 16 -1 (-2050 4000)(-1575 4000);
FORCEPROP 2 LAST SIG_NAME LED_POSTCODE_1_R
J 2
(-1625 4010);
DISPLAY 0.617021 (-1625 4010);
PAINT ORANGE (-1625 4010);
WIRE 16 -1 (-2050 3950)(-1575 3950);
FORCEPROP 2 LAST SIG_NAME LED_POSTCODE_2_R
J 0
(-2025 3960);
DISPLAY 0.617021 (-2025 3960);
PAINT ORANGE (-2025 3960);
WIRE 16 -1 (-2050 3900)(-1575 3900);
FORCEPROP 2 LAST SIG_NAME LED_POSTCODE_3_R
J 2
(-1625 3910);
DISPLAY 0.617021 (-1625 3910);
PAINT ORANGE (-1625 3910);
WIRE 16 -1 (-2050 3850)(-1575 3850);
FORCEPROP 2 LAST SIG_NAME LED_POSTCODE_4_R
J 0
(-2025 3860);
DISPLAY 0.617021 (-2025 3860);
PAINT ORANGE (-2025 3860);
WIRE 16 -1 (-2050 3750)(-1575 3750);
FORCEPROP 2 LAST SIG_NAME LED_POSTCODE_6_R
J 0
(-2025 3760);
DISPLAY 0.617021 (-2025 3760);
PAINT ORANGE (-2025 3760);
WIRE 16 -1 (-2050 3600)(-1575 3600);
FORCEPROP 2 LAST SIG_NAME FM_DEBUG_RST_BTN_N
J 0
(-1985 3610);
DISPLAY 0.680851 (-1985 3610);
PAINT ORANGE (-1985 3610);
WIRE 16 -1 (-2050 3550)(-1575 3550);
FORCEPROP 2 LAST SIG_NAME FP_PWR_BTN_R_N
J 0
(-1985 3560);
DISPLAY 0.680851 (-1985 3560);
PAINT ORANGE (-1985 3560);
WIRE 16 -1 (-2750 3750)(-3175 3750);
FORCEPROP 2 LAST SIG_NAME PCA9555_A0
J 0
(-3185 3760);
DISPLAY 0.680851 (-3185 3760);
PAINT ORANGE (-3185 3760);
FORCEPROP 2 LASTPROP $XR0 247 
J 0
(-3301 3750);
DISPLAY 0.638298 (-3301 3750);
PAINT MONO (-3301 3750);
WIRE 16 -1 (-2750 3350)(-3425 3350);
FORCEPROP 2 LAST SIG_NAME SMB_IPMB_3V3AUX_SCL
J 0
(-3385 3360);
DISPLAY 0.680851 (-3385 3360);
PAINT ORANGE (-3385 3360);
WIRE 16 -1 (-2750 3450)(-3425 3450);
FORCEPROP 2 LAST SIG_NAME SMB_IPMB_3V3AUX_SDA
J 0
(-3385 3460);
DISPLAY 0.680851 (-3385 3460);
PAINT ORANGE (-3385 3460);
WIRE 16 -1 (-7375 3700)(-7375 3300);
WIRE 16 -1 (-7375 3300)(-6400 3300);
FORCEPROP 2 LAST SIG_NAME PCA9555_INT_N
J 0
(-7085 3310);
DISPLAY 0.680851 (-7085 3310);
PAINT ORANGE (-7085 3310);
FORCEPROP 2 LASTPROP $XR0 247 
J 0
(-6495 3300);
DISPLAY 0.638298 (-6495 3300);
PAINT MONO (-6495 3300);
WIRE 16 -1 (-6850 3700)(-6850 3525);
WIRE 16 -1 (-6850 3525)(-6400 3525);
FORCEPROP 2 LAST SIG_NAME SMB_IPMB_3V3AUX_SDA
J 0
(-6810 3535);
DISPLAY 0.680851 (-6810 3535);
PAINT ORANGE (-6810 3535);
FORCEPROP 2 LASTPROP $XR0 144 
J 0
(-6190 3525);
DISPLAY 0.638298 (-6190 3525);
PAINT MONO (-6190 3525);
FORCEPROP 2 LASTPROP $XR1 176 
J 0
(-6070 3525);
DISPLAY 0.638298 (-6070 3525);
PAINT MONO (-6070 3525);
FORCEPROP 2 LASTPROP $XR2 247 
J 0
(-5950 3525);
DISPLAY 0.638298 (-5950 3525);
PAINT MONO (-5950 3525);
WIRE 16 -1 (-5650 3525)(-5650 3800);
WIRE 16 -1 (-5650 3800)(-5650 3950);
WIRE 16 -1 (-5650 3800)(-4550 3800);
FORCEPROP 2 LAST SIG_NAME PCA9555_A2
J 0
(-4810 3810);
DISPLAY 0.680851 (-4810 3810);
PAINT ORANGE (-4810 3810);
FORCEPROP 2 LASTPROP $XR0 247 
J 0
(-4460 3800);
DISPLAY 0.638298 (-4460 3800);
PAINT MONO (-4460 3800);
WIRE 16 -1 (-950 1750)(-375 1750);
FORCEPROP 2 LAST SIG_NAME SMB_HOST_STBY_LVC3_SDA
J 0
(-935 1760);
DISPLAY 0.680851 (-935 1760);
PAINT ORANGE (-935 1760);
WIRE 16 -1 (-3325 1750)(-2500 1750);
FORCEPROP 2 LAST SIG_NAME SMB_HOST_STBY_LVC3_SCL_R3
J 0
(-3260 1760);
DISPLAY 0.680851 (-3260 1760);
PAINT ORANGE (-3260 1760);
FORCEPROP 2 LASTPROP $XRERR UNIQUE?
J 0
(-3500 1760);
DISPLAY 0.638298 (-3500 1760);
PAINT MONO (-3500 1760);
DISPLAY INVISIBLE (-3500 1760);
WIRE 16 -1 (-1900 1750)(-1150 1750);
FORCEPROP 2 LAST SIG_NAME SMB_HOST_STBY_LVC3_SDA_R3
J 0
(-1810 1760);
DISPLAY 0.680851 (-1810 1760);
PAINT ORANGE (-1810 1760);
FORCEPROP 2 LASTPROP $XRERR UNIQUE?
J 0
(-2050 1760);
DISPLAY 0.638298 (-2050 1760);
PAINT MONO (-2050 1760);
DISPLAY INVISIBLE (-2050 1760);
WIRE 16 -1 (-3000 1950)(-2500 1950);
FORCEPROP 2 LAST SIG_NAME PU_ID_EEPROM_A2
J 0
(-2985 1960);
DISPLAY 0.617021 (-2985 1960);
PAINT ORANGE (-2985 1960);
FORCEPROP 2 LASTPROP $XRERR UNIQUE?
J 0
(-3225 1960);
DISPLAY 0.638298 (-3225 1960);
PAINT MONO (-3225 1960);
DISPLAY INVISIBLE (-3225 1960);
WIRE 16 -1 (-3000 2100)(-3000 1950);
WIRE 16 -1 (-3000 1700)(-3000 1625);
WIRE 16 -1 (-2500 1700)(-3000 1700);
FORCEPROP 2 LAST SIG_NAME PD_ID_EEPROM_WP
J 0
(-2960 1710);
DISPLAY 0.617021 (-2960 1710);
PAINT ORANGE (-2960 1710);
FORCEPROP 2 LASTPROP $XRERR UNIQUE?
J 0
(-3200 1710);
DISPLAY 0.638298 (-3200 1710);
PAINT MONO (-3200 1710);
DISPLAY INVISIBLE (-3200 1710);
WIRE 16 -1 (-6100 1550)(-5275 1550);
FORCEPROP 2 LAST SIG_NAME HSC_SMBUS_SWITCH_EN
J 0
(-5910 1560);
DISPLAY 0.680851 (-5910 1560);
PAINT ORANGE (-5910 1560);
WIRE 16 -1 (-4100 1750)(-3525 1750);
FORCEPROP 2 LAST SIG_NAME SMB_HOST_STBY_LVC3_SCL
J 0
(-4110 1760);
DISPLAY 0.680851 (-4110 1760);
PAINT ORANGE (-4110 1760);
WIRE 16 -1 (-5275 1600)(-6100 1600);
FORCEPROP 0 LAST CDS_PHYS_NET_NAME SMB_BMC_PMBUS_STBY_LVC3_SDA
J 0
(-5325 1639);
PAINT MONO (-5325 1639);
DISPLAY INVISIBLE (-5325 1639);
FORCEPROP 2 LAST SIG_NAME SMB_BMC_PMBUS_STBY_LVC3_SDA
J 2
(-5325 1610);
DISPLAY 0.617021 (-5325 1610);
PAINT ORANGE (-5325 1610);
WIRE 16 -1 (-7525 1600)(-6850 1600);
FORCEPROP 0 LAST CDS_PHYS_NET_NAME SMB_PMBUS_BMC_STBY_LVC3_SDA_R1
J 0
(-7550 1639);
PAINT MONO (-7550 1639);
DISPLAY INVISIBLE (-7550 1639);
FORCEPROP 2 LAST SIG_NAME SMB_PMBUS_BMC_STBY_LVC3_SDA_R1
J 0
(-7550 1610);
DISPLAY 0.617021 (-7550 1610);
PAINT ORANGE (-7550 1610);
WIRE 16 -1 (-7525 1650)(-6850 1650);
FORCEPROP 0 LAST CDS_PHYS_NET_NAME SMB_PMBUS_BMC_STBY_LVC3_SCL_R1
J 0
(-7525 1689);
PAINT MONO (-7525 1689);
DISPLAY INVISIBLE (-7525 1689);
FORCEPROP 2 LAST SIG_NAME SMB_PMBUS_BMC_STBY_LVC3_SCL_R1
J 0
(-7525 1660);
DISPLAY 0.617021 (-7525 1660);
PAINT ORANGE (-7525 1660);
WIRE 16 -1 (-7150 3400)(-6400 3400);
FORCEPROP 2 LAST SIG_NAME SMB_IPMB_3V3AUX_SCL
J 0
(-7085 3410);
DISPLAY 0.680851 (-7085 3410);
PAINT ORANGE (-7085 3410);
FORCEPROP 2 LASTPROP $XR0 144 
J 0
(-6370 3400);
DISPLAY 0.638298 (-6370 3400);
PAINT MONO (-6370 3400);
FORCEPROP 2 LASTPROP $XR1 176 
J 0
(-6250 3400);
DISPLAY 0.638298 (-6250 3400);
PAINT MONO (-6250 3400);
FORCEPROP 2 LASTPROP $XR2 247 
J 0
(-6130 3400);
DISPLAY 0.638298 (-6130 3400);
PAINT MONO (-6130 3400);
WIRE 16 -1 (-7150 3700)(-7150 3400);
WIRE 16 -1 (-4850 3950)(-4850 3600);
WIRE 16 -1 (-4850 3600)(-4550 3600);
FORCEPROP 2 LAST SIG_NAME PCA9555_A0
J 0
(-4810 3610);
DISPLAY 0.680851 (-4810 3610);
PAINT ORANGE (-4810 3610);
FORCEPROP 2 LASTPROP $XR0 247 
J 0
(-4460 3600);
DISPLAY 0.638298 (-4460 3600);
PAINT MONO (-4460 3600);
WIRE 16 -1 (-4850 3500)(-4850 3600);
WIRE 16 -1 (-5250 3950)(-5250 3700);
WIRE 16 -1 (-5250 3700)(-4550 3700);
FORCEPROP 2 LAST SIG_NAME PCA9555_A1
J 0
(-4810 3710);
DISPLAY 0.680851 (-4810 3710);
PAINT ORANGE (-4810 3710);
FORCEPROP 2 LASTPROP $XR0 247 
J 0
(-4460 3700);
DISPLAY 0.638298 (-4460 3700);
PAINT MONO (-4460 3700);
WIRE 16 -1 (-5250 3525)(-5250 3700);
DOT 1 (-5650 3800);
DOT 1 (-4850 3600);
DOT 1 (-3600 4200);
DOT 1 (-5250 4250);
DOT 1 (-5250 3700);
DOT 1 (-5650 4250);
DOT 1 (-7375 4100);
DOT 1 (-7150 4100);
DOT 1 (-6100 2175);
DOT 1 (-2575 1850);
FORCENOTE
CONNECT TO SWITCH DIRECTLY
(-1825 3425) 0;
DISPLAY LEFT (-1825 3425);
DISPLAY 1.021277 (-1825 3425);
PAINT PURPLE (-1825 3425);
FORCENOTE
TP FAB1 ADD USB3.0 BEBUG PORT 1117
(-7550 4575) 0;
DISPLAY LEFT (-7550 4575);
DISPLAY 1.021277 (-7550 4575);
PAINT RED (-7550 4575);
FORCENOTE
ADDRESS 0X40
(-2775 4525) 0;
DISPLAY LEFT (-2775 4525);
DISPLAY 1.021277 (-2775 4525);
PAINT PURPLE (-2775 4525);
FORCENOTE
SMBUS ADDRESS 0XA8
(-1825 1125) 0;
DISPLAY LEFT (-1825 1125);
DISPLAY 1.021277 (-1825 1125);
PAINT PURPLE (-1825 1125);
FORCENOTE
TP FAB1 ADD  MUX FOR HSC ACCESS FROM ME OR BMC, CONTROLLED BY BMC 1127
(-7825 2550) 0;
DISPLAY LEFT (-7825 2550);
DISPLAY 1.021277 (-7825 2550);
PAINT RED (-7825 2550);
QUIT
